FILE_TYPE = MACRO_DRAWING;
SET COLOR_WIRE YELLOW;
SET COLOR_PROP ORANGE;
SET COLOR_DOT WHITE;
SET COLOR_ARC YELLOW;
SET COLOR_BODY GREEN;
SET COLOR_NOTE PURPLE;
SET PROP_DISPLAY VALUE;
SET PAGE_NUMBER P73;
FORCEADD Q_CAP..1
(400 1075);
FORCEPROP 1 LAST LOCATION C3912
J 0
(450 1175);
DISPLAY 0.489362 (450 1175);
PAINT SKYBLUE (450 1175);
FORCEPROP 2 LAST $SEC 1
J 0
(450 1275);
DISPLAY 0.680851 (450 1275);
PAINT MONO (450 1275);
DISPLAY INVISIBLE (450 1275);
FORCEPROP 2 LAST CDS_SEC 1
J 0
(450 1275);
DISPLAY 1.021277 (450 1275);
DISPLAY INVISIBLE (450 1275);
FORCEPROP 1 LASTPIN (400 1175) $PN 1
J 0
(410 1155);
DISPLAY 0.489362 (410 1155);
FORCEPROP 1 LASTPIN (400 975) $PN 2
J 0
(410 955);
DISPLAY 0.489362 (410 955);
FORCEPROP 1 LAST MATERIAL X6S
J 0
(450 975);
DISPLAY 0.489362 (450 975);
PAINT SKYBLUE (450 975);
FORCEPROP 1 LAST TOLERANCE 20%
J 0
(450 1025);
DISPLAY 0.489362 (450 1025);
PAINT SKYBLUE (450 1025);
FORCEPROP 1 LAST VALUE 22UF
J 0
(450 1125);
DISPLAY 0.489362 (450 1125);
PAINT SKYBLUE (450 1125);
FORCEPROP 1 LAST PART_NUMBER CH622KMEB02
J 0
(450 925);
DISPLAY 0.489362 (450 925);
PAINT SKYBLUE (450 925);
FORCEPROP 1 LAST VOLTAGE 4V
J 0
(450 1075);
DISPLAY 0.489362 (450 1075);
PAINT SKYBLUE (450 1075);
FORCEPROP 1 LAST PACK_TYPE C0402
J 0
(450 875);
DISPLAY 0.489362 (450 875);
PAINT SKYBLUE (450 875);
FORCEPROP 2 LAST CDS_LIB pure_quanta
J 0
(400 1075);
PAINT MONO (400 1075);
DISPLAY INVISIBLE (400 1075);
FORCEPROP 1 LAST PATH I1
J 0
(450 1225);
DISPLAY 0.978723 (450 1225);
PAINT WHITE (450 1225);
DISPLAY INVISIBLE (450 1225);
FORCEADD UNIVERSAL_POWER..1
(400 2075);
FORCEPROP 3 LASTPIN (400 2025) SIG_NAME PVDDCR_SOC_P1\g
J 0
(410 2035);
DISPLAY 0.659574 (410 2035);
PAINT MONO (410 2035);
DISPLAY INVISIBLE (410 2035);
FORCEPROP 1 LAST HDL_POWER PVDDCR_SOC_P1
J 1
(400 2125);
DISPLAY 0.489362 (400 2125);
PAINT GREEN (400 2125);
FORCEPROP 2 LAST CDS_LIB pure_quanta_power
J 0
(400 2075);
DISPLAY INVISIBLE (400 2075);
FORCEPROP 1 LAST PATH I10
J 0
(450 2100);
DISPLAY 0.872340 (450 2100);
PAINT AQUA (450 2100);
DISPLAY INVISIBLE (450 2100);
FORCEADD Q_CAP..1
(5450 2650);
FORCEPROP 1 LAST LOCATION C2486
J 0
(5500 2750);
DISPLAY 0.489362 (5500 2750);
PAINT SKYBLUE (5500 2750);
FORCEPROP 2 LAST $SEC 1
J 0
(5500 2850);
DISPLAY 0.680851 (5500 2850);
PAINT MONO (5500 2850);
DISPLAY INVISIBLE (5500 2850);
FORCEPROP 2 LAST CDS_SEC 1
J 0
(5500 2850);
DISPLAY 1.021277 (5500 2850);
DISPLAY INVISIBLE (5500 2850);
FORCEPROP 1 LASTPIN (5450 2750) $PN 1
J 0
(5460 2730);
DISPLAY 0.489362 (5460 2730);
FORCEPROP 1 LASTPIN (5450 2550) $PN 2
J 0
(5460 2530);
DISPLAY 0.489362 (5460 2530);
FORCEPROP 1 LAST MATERIAL X6S
J 0
(5500 2550);
DISPLAY 0.489362 (5500 2550);
PAINT SKYBLUE (5500 2550);
FORCEPROP 1 LAST TOLERANCE 20%
J 0
(5500 2600);
DISPLAY 0.489362 (5500 2600);
PAINT SKYBLUE (5500 2600);
FORCEPROP 1 LAST VALUE 22UF
J 0
(5500 2700);
DISPLAY 0.489362 (5500 2700);
PAINT SKYBLUE (5500 2700);
FORCEPROP 1 LAST PART_NUMBER CH622KMEB02
J 0
(5500 2500);
DISPLAY 0.489362 (5500 2500);
PAINT SKYBLUE (5500 2500);
FORCEPROP 1 LAST VOLTAGE 4V
J 0
(5500 2650);
DISPLAY 0.489362 (5500 2650);
PAINT SKYBLUE (5500 2650);
FORCEPROP 1 LAST PACK_TYPE C0402
J 0
(5500 2450);
DISPLAY 0.489362 (5500 2450);
PAINT SKYBLUE (5500 2450);
FORCEPROP 2 LAST CDS_LIB pure_quanta
J 0
(5450 2650);
PAINT MONO (5450 2650);
DISPLAY INVISIBLE (5450 2650);
FORCEPROP 1 LAST PATH I100
J 0
(5500 2800);
DISPLAY 0.978723 (5500 2800);
PAINT WHITE (5500 2800);
DISPLAY INVISIBLE (5500 2800);
FORCEADD Q_CAP..1
(5900 2025);
FORCEPROP 1 LAST LOCATION C2491
J 0
(5950 2125);
DISPLAY 0.489362 (5950 2125);
PAINT SKYBLUE (5950 2125);
FORCEPROP 2 LAST $SEC 1
J 0
(5950 2225);
DISPLAY 0.680851 (5950 2225);
PAINT MONO (5950 2225);
DISPLAY INVISIBLE (5950 2225);
FORCEPROP 2 LAST CDS_SEC 1
J 0
(5950 2225);
DISPLAY 1.021277 (5950 2225);
DISPLAY INVISIBLE (5950 2225);
FORCEPROP 1 LASTPIN (5900 2125) $PN 1
J 0
(5910 2105);
DISPLAY 0.489362 (5910 2105);
FORCEPROP 1 LASTPIN (5900 1925) $PN 2
J 0
(5910 1905);
DISPLAY 0.489362 (5910 1905);
FORCEPROP 1 LAST MATERIAL X6S
J 0
(5950 1925);
DISPLAY 0.489362 (5950 1925);
PAINT SKYBLUE (5950 1925);
FORCEPROP 1 LAST TOLERANCE 20%
J 0
(5950 1975);
DISPLAY 0.489362 (5950 1975);
PAINT SKYBLUE (5950 1975);
FORCEPROP 1 LAST VALUE 22UF
J 0
(5950 2075);
DISPLAY 0.489362 (5950 2075);
PAINT SKYBLUE (5950 2075);
FORCEPROP 1 LAST PART_NUMBER CH622KMEB02
J 0
(5950 1875);
DISPLAY 0.489362 (5950 1875);
PAINT SKYBLUE (5950 1875);
FORCEPROP 1 LAST VOLTAGE 4V
J 0
(5950 2025);
DISPLAY 0.489362 (5950 2025);
PAINT SKYBLUE (5950 2025);
FORCEPROP 1 LAST PACK_TYPE C0402
J 0
(5950 1825);
DISPLAY 0.489362 (5950 1825);
PAINT SKYBLUE (5950 1825);
FORCEPROP 2 LAST CDS_LIB pure_quanta
J 0
(5900 2025);
PAINT MONO (5900 2025);
DISPLAY INVISIBLE (5900 2025);
FORCEPROP 1 LAST PATH I101
J 0
(5950 2175);
DISPLAY 0.978723 (5950 2175);
PAINT WHITE (5950 2175);
DISPLAY INVISIBLE (5950 2175);
FORCEADD Q_CAP..1
(5900 2650);
FORCEPROP 1 LAST LOCATION C2490
J 0
(5950 2750);
DISPLAY 0.489362 (5950 2750);
PAINT SKYBLUE (5950 2750);
FORCEPROP 2 LAST $SEC 1
J 0
(5950 2850);
DISPLAY 0.680851 (5950 2850);
PAINT MONO (5950 2850);
DISPLAY INVISIBLE (5950 2850);
FORCEPROP 2 LAST CDS_SEC 1
J 0
(5950 2850);
DISPLAY 1.021277 (5950 2850);
DISPLAY INVISIBLE (5950 2850);
FORCEPROP 1 LASTPIN (5900 2750) $PN 1
J 0
(5910 2730);
DISPLAY 0.489362 (5910 2730);
FORCEPROP 1 LASTPIN (5900 2550) $PN 2
J 0
(5910 2530);
DISPLAY 0.489362 (5910 2530);
FORCEPROP 1 LAST MATERIAL X6S
J 0
(5950 2550);
DISPLAY 0.489362 (5950 2550);
PAINT SKYBLUE (5950 2550);
FORCEPROP 1 LAST TOLERANCE 20%
J 0
(5950 2600);
DISPLAY 0.489362 (5950 2600);
PAINT SKYBLUE (5950 2600);
FORCEPROP 1 LAST VALUE 22UF
J 0
(5950 2700);
DISPLAY 0.489362 (5950 2700);
PAINT SKYBLUE (5950 2700);
FORCEPROP 1 LAST PART_NUMBER CH622KMEB02
J 0
(5950 2500);
DISPLAY 0.489362 (5950 2500);
PAINT SKYBLUE (5950 2500);
FORCEPROP 1 LAST VOLTAGE 4V
J 0
(5950 2650);
DISPLAY 0.489362 (5950 2650);
PAINT SKYBLUE (5950 2650);
FORCEPROP 1 LAST PACK_TYPE C0402
J 0
(5950 2450);
DISPLAY 0.489362 (5950 2450);
PAINT SKYBLUE (5950 2450);
FORCEPROP 2 LAST CDS_LIB pure_quanta
J 0
(5900 2650);
PAINT MONO (5900 2650);
DISPLAY INVISIBLE (5900 2650);
FORCEPROP 1 LAST PATH I102
J 0
(5950 2800);
DISPLAY 0.978723 (5950 2800);
PAINT WHITE (5950 2800);
DISPLAY INVISIBLE (5950 2800);
FORCEADD Q_CAP..1
(5450 3325);
FORCEPROP 1 LAST LOCATION C2485
J 0
(5500 3425);
DISPLAY 0.489362 (5500 3425);
PAINT SKYBLUE (5500 3425);
FORCEPROP 2 LAST $SEC 1
J 0
(5500 3525);
DISPLAY 0.680851 (5500 3525);
PAINT MONO (5500 3525);
DISPLAY INVISIBLE (5500 3525);
FORCEPROP 2 LAST CDS_SEC 1
J 0
(5500 3525);
DISPLAY 1.021277 (5500 3525);
DISPLAY INVISIBLE (5500 3525);
FORCEPROP 1 LASTPIN (5450 3425) $PN 1
J 0
(5460 3405);
DISPLAY 0.489362 (5460 3405);
FORCEPROP 1 LASTPIN (5450 3225) $PN 2
J 0
(5460 3205);
DISPLAY 0.489362 (5460 3205);
FORCEPROP 1 LAST MATERIAL X6S
J 0
(5500 3225);
DISPLAY 0.489362 (5500 3225);
PAINT SKYBLUE (5500 3225);
FORCEPROP 1 LAST TOLERANCE 20%
J 0
(5500 3275);
DISPLAY 0.489362 (5500 3275);
PAINT SKYBLUE (5500 3275);
FORCEPROP 1 LAST VALUE 22UF
J 0
(5500 3375);
DISPLAY 0.489362 (5500 3375);
PAINT SKYBLUE (5500 3375);
FORCEPROP 1 LAST PART_NUMBER CH622KMEB02
J 0
(5500 3175);
DISPLAY 0.489362 (5500 3175);
PAINT SKYBLUE (5500 3175);
FORCEPROP 1 LAST VOLTAGE 4V
J 0
(5500 3325);
DISPLAY 0.489362 (5500 3325);
PAINT SKYBLUE (5500 3325);
FORCEPROP 1 LAST PACK_TYPE C0402
J 0
(5500 3125);
DISPLAY 0.489362 (5500 3125);
PAINT SKYBLUE (5500 3125);
FORCEPROP 2 LAST CDS_LIB pure_quanta
J 0
(5450 3325);
PAINT MONO (5450 3325);
DISPLAY INVISIBLE (5450 3325);
FORCEPROP 1 LAST PATH I103
J 0
(5500 3475);
DISPLAY 0.978723 (5500 3475);
PAINT WHITE (5500 3475);
DISPLAY INVISIBLE (5500 3475);
FORCEADD Q_CAP..1
(5900 3325);
FORCEPROP 1 LAST LOCATION C2489
J 0
(5950 3425);
DISPLAY 0.489362 (5950 3425);
PAINT SKYBLUE (5950 3425);
FORCEPROP 2 LAST $SEC 1
J 0
(5950 3525);
DISPLAY 0.680851 (5950 3525);
PAINT MONO (5950 3525);
DISPLAY INVISIBLE (5950 3525);
FORCEPROP 2 LAST CDS_SEC 1
J 0
(5950 3525);
DISPLAY 1.021277 (5950 3525);
DISPLAY INVISIBLE (5950 3525);
FORCEPROP 1 LASTPIN (5900 3425) $PN 1
J 0
(5910 3405);
DISPLAY 0.489362 (5910 3405);
FORCEPROP 1 LASTPIN (5900 3225) $PN 2
J 0
(5910 3205);
DISPLAY 0.489362 (5910 3205);
FORCEPROP 1 LAST MATERIAL X6S
J 0
(5950 3225);
DISPLAY 0.489362 (5950 3225);
PAINT SKYBLUE (5950 3225);
FORCEPROP 1 LAST TOLERANCE 20%
J 0
(5950 3275);
DISPLAY 0.489362 (5950 3275);
PAINT SKYBLUE (5950 3275);
FORCEPROP 1 LAST VALUE 22UF
J 0
(5950 3375);
DISPLAY 0.489362 (5950 3375);
PAINT SKYBLUE (5950 3375);
FORCEPROP 1 LAST PART_NUMBER CH622KMEB02
J 0
(5950 3175);
DISPLAY 0.489362 (5950 3175);
PAINT SKYBLUE (5950 3175);
FORCEPROP 1 LAST VOLTAGE 4V
J 0
(5950 3325);
DISPLAY 0.489362 (5950 3325);
PAINT SKYBLUE (5950 3325);
FORCEPROP 1 LAST PACK_TYPE C0402
J 0
(5950 3125);
DISPLAY 0.489362 (5950 3125);
PAINT SKYBLUE (5950 3125);
FORCEPROP 2 LAST CDS_LIB pure_quanta
J 0
(5900 3325);
PAINT MONO (5900 3325);
DISPLAY INVISIBLE (5900 3325);
FORCEPROP 1 LAST PATH I104
J 0
(5950 3475);
DISPLAY 0.978723 (5950 3475);
PAINT WHITE (5950 3475);
DISPLAY INVISIBLE (5950 3475);
FORCEADD Q_CAP..1
(6350 1375);
FORCEPROP 1 LAST LOCATION C2497
J 0
(6400 1475);
DISPLAY 0.489362 (6400 1475);
PAINT SKYBLUE (6400 1475);
FORCEPROP 2 LAST $SEC 1
J 0
(6400 1575);
DISPLAY 0.680851 (6400 1575);
PAINT MONO (6400 1575);
DISPLAY INVISIBLE (6400 1575);
FORCEPROP 2 LAST CDS_SEC 1
J 0
(6400 1575);
DISPLAY 1.021277 (6400 1575);
DISPLAY INVISIBLE (6400 1575);
FORCEPROP 1 LASTPIN (6350 1475) $PN 1
J 0
(6360 1455);
DISPLAY 0.489362 (6360 1455);
FORCEPROP 1 LASTPIN (6350 1275) $PN 2
J 0
(6360 1255);
DISPLAY 0.489362 (6360 1255);
FORCEPROP 1 LAST MATERIAL X6S
J 0
(6400 1275);
DISPLAY 0.489362 (6400 1275);
PAINT SKYBLUE (6400 1275);
FORCEPROP 1 LAST TOLERANCE 20%
J 0
(6400 1325);
DISPLAY 0.489362 (6400 1325);
PAINT SKYBLUE (6400 1325);
FORCEPROP 1 LAST VALUE 22UF
J 0
(6400 1425);
DISPLAY 0.489362 (6400 1425);
PAINT SKYBLUE (6400 1425);
FORCEPROP 1 LAST PART_NUMBER CH622KMEB02
J 0
(6400 1225);
DISPLAY 0.489362 (6400 1225);
PAINT SKYBLUE (6400 1225);
FORCEPROP 1 LAST VOLTAGE 4V
J 0
(6400 1375);
DISPLAY 0.489362 (6400 1375);
PAINT SKYBLUE (6400 1375);
FORCEPROP 1 LAST PACK_TYPE C0402
J 0
(6400 1175);
DISPLAY 0.489362 (6400 1175);
PAINT SKYBLUE (6400 1175);
FORCEPROP 2 LAST CDS_LIB pure_quanta
J 0
(6350 1375);
PAINT MONO (6350 1375);
DISPLAY INVISIBLE (6350 1375);
FORCEPROP 1 LAST PATH I105
J 0
(6400 1525);
DISPLAY 0.978723 (6400 1525);
PAINT WHITE (6400 1525);
DISPLAY INVISIBLE (6400 1525);
FORCEADD Q_CAP..1
(6800 1375);
FORCEPROP 1 LAST LOCATION C2502
J 0
(6850 1475);
DISPLAY 0.489362 (6850 1475);
PAINT SKYBLUE (6850 1475);
FORCEPROP 2 LAST $SEC 1
J 0
(6850 1575);
DISPLAY 0.680851 (6850 1575);
PAINT MONO (6850 1575);
DISPLAY INVISIBLE (6850 1575);
FORCEPROP 2 LAST CDS_SEC 1
J 0
(6850 1575);
DISPLAY 1.021277 (6850 1575);
DISPLAY INVISIBLE (6850 1575);
FORCEPROP 1 LASTPIN (6800 1475) $PN 1
J 0
(6810 1455);
DISPLAY 0.489362 (6810 1455);
FORCEPROP 1 LASTPIN (6800 1275) $PN 2
J 0
(6810 1255);
DISPLAY 0.489362 (6810 1255);
FORCEPROP 1 LAST MATERIAL X6S
J 0
(6850 1275);
DISPLAY 0.489362 (6850 1275);
PAINT SKYBLUE (6850 1275);
FORCEPROP 1 LAST TOLERANCE 20%
J 0
(6850 1325);
DISPLAY 0.489362 (6850 1325);
PAINT SKYBLUE (6850 1325);
FORCEPROP 1 LAST VALUE 22UF
J 0
(6850 1425);
DISPLAY 0.489362 (6850 1425);
PAINT SKYBLUE (6850 1425);
FORCEPROP 1 LAST PART_NUMBER CH622KMEB02
J 0
(6850 1225);
DISPLAY 0.489362 (6850 1225);
PAINT SKYBLUE (6850 1225);
FORCEPROP 1 LAST VOLTAGE 4V
J 0
(6850 1375);
DISPLAY 0.489362 (6850 1375);
PAINT SKYBLUE (6850 1375);
FORCEPROP 1 LAST PACK_TYPE C0402
J 0
(6850 1175);
DISPLAY 0.489362 (6850 1175);
PAINT SKYBLUE (6850 1175);
FORCEPROP 2 LAST CDS_LIB pure_quanta
J 0
(6800 1375);
PAINT MONO (6800 1375);
DISPLAY INVISIBLE (6800 1375);
FORCEPROP 1 LAST PATH I106
J 0
(6850 1525);
DISPLAY 0.978723 (6850 1525);
PAINT WHITE (6850 1525);
DISPLAY INVISIBLE (6850 1525);
FORCEADD Q_CAP..1
(7250 1375);
FORCEPROP 1 LAST LOCATION C2506
J 0
(7300 1475);
DISPLAY 0.489362 (7300 1475);
PAINT SKYBLUE (7300 1475);
FORCEPROP 2 LAST $SEC 1
J 0
(7300 1575);
DISPLAY 0.680851 (7300 1575);
PAINT MONO (7300 1575);
DISPLAY INVISIBLE (7300 1575);
FORCEPROP 2 LAST CDS_SEC 1
J 0
(7300 1575);
DISPLAY 1.021277 (7300 1575);
DISPLAY INVISIBLE (7300 1575);
FORCEPROP 1 LASTPIN (7250 1475) $PN 1
J 0
(7260 1455);
DISPLAY 0.489362 (7260 1455);
FORCEPROP 1 LASTPIN (7250 1275) $PN 2
J 0
(7260 1255);
DISPLAY 0.489362 (7260 1255);
FORCEPROP 1 LAST MATERIAL X6S
J 0
(7300 1275);
DISPLAY 0.489362 (7300 1275);
PAINT SKYBLUE (7300 1275);
FORCEPROP 1 LAST TOLERANCE 20%
J 0
(7300 1325);
DISPLAY 0.489362 (7300 1325);
PAINT SKYBLUE (7300 1325);
FORCEPROP 1 LAST VALUE 22UF
J 0
(7300 1425);
DISPLAY 0.489362 (7300 1425);
PAINT SKYBLUE (7300 1425);
FORCEPROP 1 LAST PART_NUMBER CH622KMEB02
J 0
(7300 1225);
DISPLAY 0.489362 (7300 1225);
PAINT SKYBLUE (7300 1225);
FORCEPROP 1 LAST VOLTAGE 4V
J 0
(7300 1375);
DISPLAY 0.489362 (7300 1375);
PAINT SKYBLUE (7300 1375);
FORCEPROP 1 LAST PACK_TYPE C0402
J 0
(7300 1175);
DISPLAY 0.489362 (7300 1175);
PAINT SKYBLUE (7300 1175);
FORCEPROP 2 LAST CDS_LIB pure_quanta
J 0
(7250 1375);
PAINT MONO (7250 1375);
DISPLAY INVISIBLE (7250 1375);
FORCEPROP 1 LAST PATH I107
J 0
(7300 1525);
DISPLAY 0.978723 (7300 1525);
PAINT WHITE (7300 1525);
DISPLAY INVISIBLE (7300 1525);
FORCEADD Q_CAP..1
(7700 1375);
FORCEPROP 1 LAST LOCATION C2115
J 0
(7750 1475);
DISPLAY 0.489362 (7750 1475);
PAINT SKYBLUE (7750 1475);
FORCEPROP 2 LAST $SEC 1
J 0
(7750 1575);
DISPLAY 0.680851 (7750 1575);
PAINT MONO (7750 1575);
DISPLAY INVISIBLE (7750 1575);
FORCEPROP 2 LAST CDS_SEC 1
J 0
(7750 1575);
DISPLAY 1.021277 (7750 1575);
DISPLAY INVISIBLE (7750 1575);
FORCEPROP 1 LASTPIN (7700 1475) $PN 1
J 0
(7710 1455);
DISPLAY 0.489362 (7710 1455);
FORCEPROP 1 LASTPIN (7700 1275) $PN 2
J 0
(7710 1255);
DISPLAY 0.489362 (7710 1255);
FORCEPROP 1 LAST MATERIAL X6S
J 0
(7750 1275);
DISPLAY 0.489362 (7750 1275);
PAINT SKYBLUE (7750 1275);
FORCEPROP 1 LAST TOLERANCE 20%
J 0
(7750 1325);
DISPLAY 0.489362 (7750 1325);
PAINT SKYBLUE (7750 1325);
FORCEPROP 1 LAST VALUE 22UF
J 0
(7750 1425);
DISPLAY 0.489362 (7750 1425);
PAINT SKYBLUE (7750 1425);
FORCEPROP 1 LAST PART_NUMBER CH622KMEB02
J 0
(7750 1225);
DISPLAY 0.489362 (7750 1225);
PAINT SKYBLUE (7750 1225);
FORCEPROP 1 LAST VOLTAGE 4V
J 0
(7750 1375);
DISPLAY 0.489362 (7750 1375);
PAINT SKYBLUE (7750 1375);
FORCEPROP 1 LAST PACK_TYPE C0402
J 0
(7750 1175);
DISPLAY 0.489362 (7750 1175);
PAINT SKYBLUE (7750 1175);
FORCEPROP 2 LAST CDS_LIB pure_quanta
J 0
(7700 1375);
PAINT MONO (7700 1375);
DISPLAY INVISIBLE (7700 1375);
FORCEPROP 1 LAST PATH I108
J 0
(7750 1525);
DISPLAY 0.978723 (7750 1525);
PAINT WHITE (7750 1525);
DISPLAY INVISIBLE (7750 1525);
FORCEADD Q_CAP..1
(8150 1375);
FORCEPROP 1 LAST LOCATION C2121
J 0
(8200 1475);
DISPLAY 0.489362 (8200 1475);
PAINT SKYBLUE (8200 1475);
FORCEPROP 2 LAST $SEC 1
J 0
(8200 1575);
DISPLAY 0.680851 (8200 1575);
PAINT MONO (8200 1575);
DISPLAY INVISIBLE (8200 1575);
FORCEPROP 2 LAST CDS_SEC 1
J 0
(8200 1575);
DISPLAY 1.021277 (8200 1575);
DISPLAY INVISIBLE (8200 1575);
FORCEPROP 1 LASTPIN (8150 1475) $PN 1
J 0
(8160 1455);
DISPLAY 0.489362 (8160 1455);
FORCEPROP 1 LASTPIN (8150 1275) $PN 2
J 0
(8160 1255);
DISPLAY 0.489362 (8160 1255);
FORCEPROP 1 LAST MATERIAL X6S
J 0
(8200 1275);
DISPLAY 0.489362 (8200 1275);
PAINT SKYBLUE (8200 1275);
FORCEPROP 1 LAST TOLERANCE 20%
J 0
(8200 1325);
DISPLAY 0.489362 (8200 1325);
PAINT SKYBLUE (8200 1325);
FORCEPROP 1 LAST VALUE 22UF
J 0
(8200 1425);
DISPLAY 0.489362 (8200 1425);
PAINT SKYBLUE (8200 1425);
FORCEPROP 1 LAST PART_NUMBER CH622KMEB02
J 0
(8200 1225);
DISPLAY 0.489362 (8200 1225);
PAINT SKYBLUE (8200 1225);
FORCEPROP 1 LAST VOLTAGE 4V
J 0
(8200 1375);
DISPLAY 0.489362 (8200 1375);
PAINT SKYBLUE (8200 1375);
FORCEPROP 1 LAST PACK_TYPE C0402
J 0
(8200 1175);
DISPLAY 0.489362 (8200 1175);
PAINT SKYBLUE (8200 1175);
FORCEPROP 2 LAST CDS_LIB pure_quanta
J 0
(8150 1375);
PAINT MONO (8150 1375);
DISPLAY INVISIBLE (8150 1375);
FORCEPROP 1 LAST PATH I109
J 0
(8200 1525);
DISPLAY 0.978723 (8200 1525);
PAINT WHITE (8200 1525);
DISPLAY INVISIBLE (8200 1525);
FORCEADD Q_CAP..1
(400 2475);
FORCEPROP 1 LAST LOCATION C2412
J 0
(450 2575);
DISPLAY 0.489362 (450 2575);
PAINT SKYBLUE (450 2575);
FORCEPROP 2 LAST $SEC 1
J 0
(450 2675);
DISPLAY 0.680851 (450 2675);
PAINT MONO (450 2675);
DISPLAY INVISIBLE (450 2675);
FORCEPROP 2 LAST CDS_SEC 1
J 0
(450 2675);
DISPLAY 1.021277 (450 2675);
DISPLAY INVISIBLE (450 2675);
FORCEPROP 1 LASTPIN (400 2575) $PN 1
J 0
(410 2555);
DISPLAY 0.489362 (410 2555);
FORCEPROP 1 LASTPIN (400 2375) $PN 2
J 0
(410 2355);
DISPLAY 0.489362 (410 2355);
FORCEPROP 1 LAST MATERIAL X6S
J 0
(450 2375);
DISPLAY 0.489362 (450 2375);
PAINT SKYBLUE (450 2375);
FORCEPROP 1 LAST TOLERANCE 20%
J 0
(450 2425);
DISPLAY 0.489362 (450 2425);
PAINT SKYBLUE (450 2425);
FORCEPROP 1 LAST VALUE 22UF
J 0
(450 2525);
DISPLAY 0.489362 (450 2525);
PAINT SKYBLUE (450 2525);
FORCEPROP 1 LAST PART_NUMBER CH622KMEB02
J 0
(450 2325);
DISPLAY 0.489362 (450 2325);
PAINT SKYBLUE (450 2325);
FORCEPROP 1 LAST VOLTAGE 4V
J 0
(450 2475);
DISPLAY 0.489362 (450 2475);
PAINT SKYBLUE (450 2475);
FORCEPROP 1 LAST PACK_TYPE C0402
J 0
(450 2275);
DISPLAY 0.489362 (450 2275);
PAINT SKYBLUE (450 2275);
FORCEPROP 2 LAST CDS_LIB pure_quanta
J 0
(400 2475);
PAINT MONO (400 2475);
DISPLAY INVISIBLE (400 2475);
FORCEPROP 1 LAST PATH I11
J 0
(450 2625);
DISPLAY 0.978723 (450 2625);
PAINT WHITE (450 2625);
DISPLAY INVISIBLE (450 2625);
FORCEADD Q_CAP..1
(6350 2025);
FORCEPROP 1 LAST LOCATION C2496
J 0
(6400 2125);
DISPLAY 0.489362 (6400 2125);
PAINT SKYBLUE (6400 2125);
FORCEPROP 2 LAST $SEC 1
J 0
(6400 2225);
DISPLAY 0.680851 (6400 2225);
PAINT MONO (6400 2225);
DISPLAY INVISIBLE (6400 2225);
FORCEPROP 2 LAST CDS_SEC 1
J 0
(6400 2225);
DISPLAY 1.021277 (6400 2225);
DISPLAY INVISIBLE (6400 2225);
FORCEPROP 1 LASTPIN (6350 2125) $PN 1
J 0
(6360 2105);
DISPLAY 0.489362 (6360 2105);
FORCEPROP 1 LASTPIN (6350 1925) $PN 2
J 0
(6360 1905);
DISPLAY 0.489362 (6360 1905);
FORCEPROP 1 LAST MATERIAL X6S
J 0
(6400 1925);
DISPLAY 0.489362 (6400 1925);
PAINT SKYBLUE (6400 1925);
FORCEPROP 1 LAST TOLERANCE 20%
J 0
(6400 1975);
DISPLAY 0.489362 (6400 1975);
PAINT SKYBLUE (6400 1975);
FORCEPROP 1 LAST VALUE 22UF
J 0
(6400 2075);
DISPLAY 0.489362 (6400 2075);
PAINT SKYBLUE (6400 2075);
FORCEPROP 1 LAST PART_NUMBER CH622KMEB02
J 0
(6400 1875);
DISPLAY 0.489362 (6400 1875);
PAINT SKYBLUE (6400 1875);
FORCEPROP 1 LAST VOLTAGE 4V
J 0
(6400 2025);
DISPLAY 0.489362 (6400 2025);
PAINT SKYBLUE (6400 2025);
FORCEPROP 1 LAST PACK_TYPE C0402
J 0
(6400 1825);
DISPLAY 0.489362 (6400 1825);
PAINT SKYBLUE (6400 1825);
FORCEPROP 2 LAST CDS_LIB pure_quanta
J 0
(6350 2025);
PAINT MONO (6350 2025);
DISPLAY INVISIBLE (6350 2025);
FORCEPROP 1 LAST PATH I110
J 0
(6400 2175);
DISPLAY 0.978723 (6400 2175);
PAINT WHITE (6400 2175);
DISPLAY INVISIBLE (6400 2175);
FORCEADD Q_CAP..1
(6350 2650);
FORCEPROP 1 LAST LOCATION C2495
J 0
(6400 2750);
DISPLAY 0.489362 (6400 2750);
PAINT SKYBLUE (6400 2750);
FORCEPROP 2 LAST $SEC 1
J 0
(6400 2850);
DISPLAY 0.680851 (6400 2850);
PAINT MONO (6400 2850);
DISPLAY INVISIBLE (6400 2850);
FORCEPROP 2 LAST CDS_SEC 1
J 0
(6400 2850);
DISPLAY 1.021277 (6400 2850);
DISPLAY INVISIBLE (6400 2850);
FORCEPROP 1 LASTPIN (6350 2750) $PN 1
J 0
(6360 2730);
DISPLAY 0.489362 (6360 2730);
FORCEPROP 1 LASTPIN (6350 2550) $PN 2
J 0
(6360 2530);
DISPLAY 0.489362 (6360 2530);
FORCEPROP 1 LAST MATERIAL X6S
J 0
(6400 2550);
DISPLAY 0.489362 (6400 2550);
PAINT SKYBLUE (6400 2550);
FORCEPROP 1 LAST TOLERANCE 20%
J 0
(6400 2600);
DISPLAY 0.489362 (6400 2600);
PAINT SKYBLUE (6400 2600);
FORCEPROP 1 LAST VALUE 22UF
J 0
(6400 2700);
DISPLAY 0.489362 (6400 2700);
PAINT SKYBLUE (6400 2700);
FORCEPROP 1 LAST PART_NUMBER CH622KMEB02
J 0
(6400 2500);
DISPLAY 0.489362 (6400 2500);
PAINT SKYBLUE (6400 2500);
FORCEPROP 1 LAST VOLTAGE 4V
J 0
(6400 2650);
DISPLAY 0.489362 (6400 2650);
PAINT SKYBLUE (6400 2650);
FORCEPROP 1 LAST PACK_TYPE C0402
J 0
(6400 2450);
DISPLAY 0.489362 (6400 2450);
PAINT SKYBLUE (6400 2450);
FORCEPROP 2 LAST CDS_LIB pure_quanta
J 0
(6350 2650);
PAINT MONO (6350 2650);
DISPLAY INVISIBLE (6350 2650);
FORCEPROP 1 LAST PATH I111
J 0
(6400 2800);
DISPLAY 0.978723 (6400 2800);
PAINT WHITE (6400 2800);
DISPLAY INVISIBLE (6400 2800);
FORCEADD Q_CAP..1
(6800 2025);
FORCEPROP 1 LAST LOCATION C2501
J 0
(6850 2125);
DISPLAY 0.489362 (6850 2125);
PAINT SKYBLUE (6850 2125);
FORCEPROP 2 LAST $SEC 1
J 0
(6850 2225);
DISPLAY 0.680851 (6850 2225);
PAINT MONO (6850 2225);
DISPLAY INVISIBLE (6850 2225);
FORCEPROP 2 LAST CDS_SEC 1
J 0
(6850 2225);
DISPLAY 1.021277 (6850 2225);
DISPLAY INVISIBLE (6850 2225);
FORCEPROP 1 LASTPIN (6800 2125) $PN 1
J 0
(6810 2105);
DISPLAY 0.489362 (6810 2105);
FORCEPROP 1 LASTPIN (6800 1925) $PN 2
J 0
(6810 1905);
DISPLAY 0.489362 (6810 1905);
FORCEPROP 1 LAST MATERIAL X6S
J 0
(6850 1925);
DISPLAY 0.489362 (6850 1925);
PAINT SKYBLUE (6850 1925);
FORCEPROP 1 LAST TOLERANCE 20%
J 0
(6850 1975);
DISPLAY 0.489362 (6850 1975);
PAINT SKYBLUE (6850 1975);
FORCEPROP 1 LAST VALUE 22UF
J 0
(6850 2075);
DISPLAY 0.489362 (6850 2075);
PAINT SKYBLUE (6850 2075);
FORCEPROP 1 LAST PART_NUMBER CH622KMEB02
J 0
(6850 1875);
DISPLAY 0.489362 (6850 1875);
PAINT SKYBLUE (6850 1875);
FORCEPROP 1 LAST VOLTAGE 4V
J 0
(6850 2025);
DISPLAY 0.489362 (6850 2025);
PAINT SKYBLUE (6850 2025);
FORCEPROP 1 LAST PACK_TYPE C0402
J 0
(6850 1825);
DISPLAY 0.489362 (6850 1825);
PAINT SKYBLUE (6850 1825);
FORCEPROP 2 LAST CDS_LIB pure_quanta
J 0
(6800 2025);
PAINT MONO (6800 2025);
DISPLAY INVISIBLE (6800 2025);
FORCEPROP 1 LAST PATH I112
J 0
(6850 2175);
DISPLAY 0.978723 (6850 2175);
PAINT WHITE (6850 2175);
DISPLAY INVISIBLE (6850 2175);
FORCEADD Q_CAP..1
(6800 2650);
FORCEPROP 1 LAST LOCATION C2500
J 0
(6850 2750);
DISPLAY 0.489362 (6850 2750);
PAINT SKYBLUE (6850 2750);
FORCEPROP 2 LAST $SEC 1
J 0
(6850 2850);
DISPLAY 0.680851 (6850 2850);
PAINT MONO (6850 2850);
DISPLAY INVISIBLE (6850 2850);
FORCEPROP 2 LAST CDS_SEC 1
J 0
(6850 2850);
DISPLAY 1.021277 (6850 2850);
DISPLAY INVISIBLE (6850 2850);
FORCEPROP 1 LASTPIN (6800 2750) $PN 1
J 0
(6810 2730);
DISPLAY 0.489362 (6810 2730);
FORCEPROP 1 LASTPIN (6800 2550) $PN 2
J 0
(6810 2530);
DISPLAY 0.489362 (6810 2530);
FORCEPROP 1 LAST MATERIAL X6S
J 0
(6850 2550);
DISPLAY 0.489362 (6850 2550);
PAINT SKYBLUE (6850 2550);
FORCEPROP 1 LAST TOLERANCE 20%
J 0
(6850 2600);
DISPLAY 0.489362 (6850 2600);
PAINT SKYBLUE (6850 2600);
FORCEPROP 1 LAST VALUE 22UF
J 0
(6850 2700);
DISPLAY 0.489362 (6850 2700);
PAINT SKYBLUE (6850 2700);
FORCEPROP 1 LAST PART_NUMBER CH622KMEB02
J 0
(6850 2500);
DISPLAY 0.489362 (6850 2500);
PAINT SKYBLUE (6850 2500);
FORCEPROP 1 LAST VOLTAGE 4V
J 0
(6850 2650);
DISPLAY 0.489362 (6850 2650);
PAINT SKYBLUE (6850 2650);
FORCEPROP 1 LAST PACK_TYPE C0402
J 0
(6850 2450);
DISPLAY 0.489362 (6850 2450);
PAINT SKYBLUE (6850 2450);
FORCEPROP 2 LAST CDS_LIB pure_quanta
J 0
(6800 2650);
PAINT MONO (6800 2650);
DISPLAY INVISIBLE (6800 2650);
FORCEPROP 1 LAST PATH I113
J 0
(6850 2800);
DISPLAY 0.978723 (6850 2800);
PAINT WHITE (6850 2800);
DISPLAY INVISIBLE (6850 2800);
FORCEADD Q_CAP..1
(6350 3325);
FORCEPROP 1 LAST LOCATION C2494
J 0
(6400 3425);
DISPLAY 0.489362 (6400 3425);
PAINT SKYBLUE (6400 3425);
FORCEPROP 2 LAST $SEC 1
J 0
(6400 3525);
DISPLAY 0.680851 (6400 3525);
PAINT MONO (6400 3525);
DISPLAY INVISIBLE (6400 3525);
FORCEPROP 2 LAST CDS_SEC 1
J 0
(6400 3525);
DISPLAY 1.021277 (6400 3525);
DISPLAY INVISIBLE (6400 3525);
FORCEPROP 1 LASTPIN (6350 3425) $PN 1
J 0
(6360 3405);
DISPLAY 0.489362 (6360 3405);
FORCEPROP 1 LASTPIN (6350 3225) $PN 2
J 0
(6360 3205);
DISPLAY 0.489362 (6360 3205);
FORCEPROP 1 LAST MATERIAL X6S
J 0
(6400 3225);
DISPLAY 0.489362 (6400 3225);
PAINT SKYBLUE (6400 3225);
FORCEPROP 1 LAST TOLERANCE 20%
J 0
(6400 3275);
DISPLAY 0.489362 (6400 3275);
PAINT SKYBLUE (6400 3275);
FORCEPROP 1 LAST VALUE 22UF
J 0
(6400 3375);
DISPLAY 0.489362 (6400 3375);
PAINT SKYBLUE (6400 3375);
FORCEPROP 1 LAST PART_NUMBER CH622KMEB02
J 0
(6400 3175);
DISPLAY 0.489362 (6400 3175);
PAINT SKYBLUE (6400 3175);
FORCEPROP 1 LAST VOLTAGE 4V
J 0
(6400 3325);
DISPLAY 0.489362 (6400 3325);
PAINT SKYBLUE (6400 3325);
FORCEPROP 1 LAST PACK_TYPE C0402
J 0
(6400 3125);
DISPLAY 0.489362 (6400 3125);
PAINT SKYBLUE (6400 3125);
FORCEPROP 2 LAST CDS_LIB pure_quanta
J 0
(6350 3325);
PAINT MONO (6350 3325);
DISPLAY INVISIBLE (6350 3325);
FORCEPROP 1 LAST PATH I114
J 0
(6400 3475);
DISPLAY 0.978723 (6400 3475);
PAINT WHITE (6400 3475);
DISPLAY INVISIBLE (6400 3475);
FORCEADD UNIVERSAL_GND..1
(6350 3925);
FORCEPROP 3 LASTPIN (6350 3975) SIG_NAME GND\g
J 0
(6360 3985);
DISPLAY 0.659574 (6360 3985);
PAINT MONO (6360 3985);
DISPLAY INVISIBLE (6360 3985);
FORCEPROP 2 LAST CDS_LIB pure_quanta_power
J 0
(6350 3925);
DISPLAY INVISIBLE (6350 3925);
FORCEPROP 1 LAST PATH I115
J 0
(6425 3925);
DISPLAY 0.872340 (6425 3925);
PAINT AQUA (6425 3925);
DISPLAY INVISIBLE (6425 3925);
FORCEPROP 1 LAST HDL_POWER GND
J 1
(6375 3850);
DISPLAY 0.872340 (6375 3850);
PAINT GREEN (6375 3850);
DISPLAY INVISIBLE (6375 3850);
FORCEADD Q_CAP..1
(6800 3325);
FORCEPROP 1 LAST LOCATION C2499
J 0
(6850 3425);
DISPLAY 0.489362 (6850 3425);
PAINT SKYBLUE (6850 3425);
FORCEPROP 2 LAST $SEC 1
J 0
(6850 3525);
DISPLAY 0.680851 (6850 3525);
PAINT MONO (6850 3525);
DISPLAY INVISIBLE (6850 3525);
FORCEPROP 2 LAST CDS_SEC 1
J 0
(6850 3525);
DISPLAY 1.021277 (6850 3525);
DISPLAY INVISIBLE (6850 3525);
FORCEPROP 1 LASTPIN (6800 3425) $PN 1
J 0
(6810 3405);
DISPLAY 0.489362 (6810 3405);
FORCEPROP 1 LASTPIN (6800 3225) $PN 2
J 0
(6810 3205);
DISPLAY 0.489362 (6810 3205);
FORCEPROP 1 LAST MATERIAL X6S
J 0
(6850 3225);
DISPLAY 0.489362 (6850 3225);
PAINT SKYBLUE (6850 3225);
FORCEPROP 1 LAST TOLERANCE 20%
J 0
(6850 3275);
DISPLAY 0.489362 (6850 3275);
PAINT SKYBLUE (6850 3275);
FORCEPROP 1 LAST VALUE 22UF
J 0
(6850 3375);
DISPLAY 0.489362 (6850 3375);
PAINT SKYBLUE (6850 3375);
FORCEPROP 1 LAST PART_NUMBER CH622KMEB02
J 0
(6850 3175);
DISPLAY 0.489362 (6850 3175);
PAINT SKYBLUE (6850 3175);
FORCEPROP 1 LAST VOLTAGE 4V
J 0
(6850 3325);
DISPLAY 0.489362 (6850 3325);
PAINT SKYBLUE (6850 3325);
FORCEPROP 1 LAST PACK_TYPE C0402
J 0
(6850 3125);
DISPLAY 0.489362 (6850 3125);
PAINT SKYBLUE (6850 3125);
FORCEPROP 2 LAST CDS_LIB pure_quanta
J 0
(6800 3325);
PAINT MONO (6800 3325);
DISPLAY INVISIBLE (6800 3325);
FORCEPROP 1 LAST PATH I116
J 0
(6850 3475);
DISPLAY 0.978723 (6850 3475);
PAINT WHITE (6850 3475);
DISPLAY INVISIBLE (6850 3475);
FORCEADD Q_CAP..1
(7250 2025);
FORCEPROP 1 LAST LOCATION C2505
J 0
(7300 2125);
DISPLAY 0.489362 (7300 2125);
PAINT SKYBLUE (7300 2125);
FORCEPROP 2 LAST $SEC 1
J 0
(7300 2225);
DISPLAY 0.680851 (7300 2225);
PAINT MONO (7300 2225);
DISPLAY INVISIBLE (7300 2225);
FORCEPROP 2 LAST CDS_SEC 1
J 0
(7300 2225);
DISPLAY 1.021277 (7300 2225);
DISPLAY INVISIBLE (7300 2225);
FORCEPROP 1 LASTPIN (7250 2125) $PN 1
J 0
(7260 2105);
DISPLAY 0.489362 (7260 2105);
FORCEPROP 1 LASTPIN (7250 1925) $PN 2
J 0
(7260 1905);
DISPLAY 0.489362 (7260 1905);
FORCEPROP 1 LAST MATERIAL X6S
J 0
(7300 1925);
DISPLAY 0.489362 (7300 1925);
PAINT SKYBLUE (7300 1925);
FORCEPROP 1 LAST TOLERANCE 20%
J 0
(7300 1975);
DISPLAY 0.489362 (7300 1975);
PAINT SKYBLUE (7300 1975);
FORCEPROP 1 LAST VALUE 22UF
J 0
(7300 2075);
DISPLAY 0.489362 (7300 2075);
PAINT SKYBLUE (7300 2075);
FORCEPROP 1 LAST PART_NUMBER CH622KMEB02
J 0
(7300 1875);
DISPLAY 0.489362 (7300 1875);
PAINT SKYBLUE (7300 1875);
FORCEPROP 1 LAST VOLTAGE 4V
J 0
(7300 2025);
DISPLAY 0.489362 (7300 2025);
PAINT SKYBLUE (7300 2025);
FORCEPROP 1 LAST PACK_TYPE C0402
J 0
(7300 1825);
DISPLAY 0.489362 (7300 1825);
PAINT SKYBLUE (7300 1825);
FORCEPROP 2 LAST CDS_LIB pure_quanta
J 0
(7250 2025);
PAINT MONO (7250 2025);
DISPLAY INVISIBLE (7250 2025);
FORCEPROP 1 LAST PATH I117
J 0
(7300 2175);
DISPLAY 0.978723 (7300 2175);
PAINT WHITE (7300 2175);
DISPLAY INVISIBLE (7300 2175);
FORCEADD Q_CAP..1
(7250 2650);
FORCEPROP 1 LAST LOCATION C2504
J 0
(7300 2750);
DISPLAY 0.489362 (7300 2750);
PAINT SKYBLUE (7300 2750);
FORCEPROP 2 LAST $SEC 1
J 0
(7300 2850);
DISPLAY 0.680851 (7300 2850);
PAINT MONO (7300 2850);
DISPLAY INVISIBLE (7300 2850);
FORCEPROP 2 LAST CDS_SEC 1
J 0
(7300 2850);
DISPLAY 1.021277 (7300 2850);
DISPLAY INVISIBLE (7300 2850);
FORCEPROP 1 LASTPIN (7250 2750) $PN 1
J 0
(7260 2730);
DISPLAY 0.489362 (7260 2730);
FORCEPROP 1 LASTPIN (7250 2550) $PN 2
J 0
(7260 2530);
DISPLAY 0.489362 (7260 2530);
FORCEPROP 1 LAST MATERIAL X6S
J 0
(7300 2550);
DISPLAY 0.489362 (7300 2550);
PAINT SKYBLUE (7300 2550);
FORCEPROP 1 LAST TOLERANCE 20%
J 0
(7300 2600);
DISPLAY 0.489362 (7300 2600);
PAINT SKYBLUE (7300 2600);
FORCEPROP 1 LAST VALUE 22UF
J 0
(7300 2700);
DISPLAY 0.489362 (7300 2700);
PAINT SKYBLUE (7300 2700);
FORCEPROP 1 LAST PART_NUMBER CH622KMEB02
J 0
(7300 2500);
DISPLAY 0.489362 (7300 2500);
PAINT SKYBLUE (7300 2500);
FORCEPROP 1 LAST VOLTAGE 4V
J 0
(7300 2650);
DISPLAY 0.489362 (7300 2650);
PAINT SKYBLUE (7300 2650);
FORCEPROP 1 LAST PACK_TYPE C0402
J 0
(7300 2450);
DISPLAY 0.489362 (7300 2450);
PAINT SKYBLUE (7300 2450);
FORCEPROP 2 LAST CDS_LIB pure_quanta
J 0
(7250 2650);
PAINT MONO (7250 2650);
DISPLAY INVISIBLE (7250 2650);
FORCEPROP 1 LAST PATH I118
J 0
(7300 2800);
DISPLAY 0.978723 (7300 2800);
PAINT WHITE (7300 2800);
DISPLAY INVISIBLE (7300 2800);
FORCEADD Q_CAP..1
(7700 2650);
FORCEPROP 1 LAST LOCATION C2113
J 0
(7750 2750);
DISPLAY 0.489362 (7750 2750);
PAINT SKYBLUE (7750 2750);
FORCEPROP 2 LAST $SEC 1
J 0
(7750 2850);
DISPLAY 0.680851 (7750 2850);
PAINT MONO (7750 2850);
DISPLAY INVISIBLE (7750 2850);
FORCEPROP 2 LAST CDS_SEC 1
J 0
(7750 2850);
DISPLAY 1.021277 (7750 2850);
DISPLAY INVISIBLE (7750 2850);
FORCEPROP 1 LASTPIN (7700 2750) $PN 1
J 0
(7710 2730);
DISPLAY 0.489362 (7710 2730);
FORCEPROP 1 LASTPIN (7700 2550) $PN 2
J 0
(7710 2530);
DISPLAY 0.489362 (7710 2530);
FORCEPROP 1 LAST MATERIAL X6S
J 0
(7750 2550);
DISPLAY 0.489362 (7750 2550);
PAINT SKYBLUE (7750 2550);
FORCEPROP 1 LAST TOLERANCE 20%
J 0
(7750 2600);
DISPLAY 0.489362 (7750 2600);
PAINT SKYBLUE (7750 2600);
FORCEPROP 1 LAST VALUE 22UF
J 0
(7750 2700);
DISPLAY 0.489362 (7750 2700);
PAINT SKYBLUE (7750 2700);
FORCEPROP 1 LAST PART_NUMBER CH622KMEB02
J 0
(7750 2500);
DISPLAY 0.489362 (7750 2500);
PAINT SKYBLUE (7750 2500);
FORCEPROP 1 LAST VOLTAGE 4V
J 0
(7750 2650);
DISPLAY 0.489362 (7750 2650);
PAINT SKYBLUE (7750 2650);
FORCEPROP 1 LAST PACK_TYPE C0402
J 0
(7750 2450);
DISPLAY 0.489362 (7750 2450);
PAINT SKYBLUE (7750 2450);
FORCEPROP 2 LAST CDS_LIB pure_quanta
J 0
(7700 2650);
PAINT MONO (7700 2650);
DISPLAY INVISIBLE (7700 2650);
FORCEPROP 1 LAST PATH I119
J 0
(7750 2800);
DISPLAY 0.978723 (7750 2800);
PAINT WHITE (7750 2800);
DISPLAY INVISIBLE (7750 2800);
FORCEADD UNIVERSAL_POWER..1
(400 2750);
FORCEPROP 3 LASTPIN (400 2700) SIG_NAME PVDDCR_SOC_P1\g
J 0
(410 2710);
DISPLAY 0.659574 (410 2710);
PAINT MONO (410 2710);
DISPLAY INVISIBLE (410 2710);
FORCEPROP 1 LAST HDL_POWER PVDDCR_SOC_P1
J 1
(400 2800);
DISPLAY 0.489362 (400 2800);
PAINT GREEN (400 2800);
FORCEPROP 2 LAST CDS_LIB pure_quanta_power
J 0
(400 2750);
DISPLAY INVISIBLE (400 2750);
FORCEPROP 1 LAST PATH I12
J 0
(450 2775);
DISPLAY 0.872340 (450 2775);
PAINT AQUA (450 2775);
DISPLAY INVISIBLE (450 2775);
FORCEADD Q_CAP..1
(7700 2025);
FORCEPROP 1 LAST LOCATION C2114
J 0
(7750 2125);
DISPLAY 0.489362 (7750 2125);
PAINT SKYBLUE (7750 2125);
FORCEPROP 2 LAST $SEC 1
J 0
(7750 2225);
DISPLAY 0.680851 (7750 2225);
PAINT MONO (7750 2225);
DISPLAY INVISIBLE (7750 2225);
FORCEPROP 2 LAST CDS_SEC 1
J 0
(7750 2225);
DISPLAY 1.021277 (7750 2225);
DISPLAY INVISIBLE (7750 2225);
FORCEPROP 1 LASTPIN (7700 2125) $PN 1
J 0
(7710 2105);
DISPLAY 0.489362 (7710 2105);
FORCEPROP 1 LASTPIN (7700 1925) $PN 2
J 0
(7710 1905);
DISPLAY 0.489362 (7710 1905);
FORCEPROP 1 LAST MATERIAL X6S
J 0
(7750 1925);
DISPLAY 0.489362 (7750 1925);
PAINT SKYBLUE (7750 1925);
FORCEPROP 1 LAST TOLERANCE 20%
J 0
(7750 1975);
DISPLAY 0.489362 (7750 1975);
PAINT SKYBLUE (7750 1975);
FORCEPROP 1 LAST VALUE 22UF
J 0
(7750 2075);
DISPLAY 0.489362 (7750 2075);
PAINT SKYBLUE (7750 2075);
FORCEPROP 1 LAST PART_NUMBER CH622KMEB02
J 0
(7750 1875);
DISPLAY 0.489362 (7750 1875);
PAINT SKYBLUE (7750 1875);
FORCEPROP 1 LAST VOLTAGE 4V
J 0
(7750 2025);
DISPLAY 0.489362 (7750 2025);
PAINT SKYBLUE (7750 2025);
FORCEPROP 1 LAST PACK_TYPE C0402
J 0
(7750 1825);
DISPLAY 0.489362 (7750 1825);
PAINT SKYBLUE (7750 1825);
FORCEPROP 2 LAST CDS_LIB pure_quanta
J 0
(7700 2025);
PAINT MONO (7700 2025);
DISPLAY INVISIBLE (7700 2025);
FORCEPROP 1 LAST PATH I120
J 0
(7750 2175);
DISPLAY 0.978723 (7750 2175);
PAINT WHITE (7750 2175);
DISPLAY INVISIBLE (7750 2175);
FORCEADD Q_CAP..1
(8150 2025);
FORCEPROP 1 LAST LOCATION C2120
J 0
(8200 2125);
DISPLAY 0.489362 (8200 2125);
PAINT SKYBLUE (8200 2125);
FORCEPROP 2 LAST $SEC 1
J 0
(8200 2225);
DISPLAY 0.680851 (8200 2225);
PAINT MONO (8200 2225);
DISPLAY INVISIBLE (8200 2225);
FORCEPROP 2 LAST CDS_SEC 1
J 0
(8200 2225);
DISPLAY 1.021277 (8200 2225);
DISPLAY INVISIBLE (8200 2225);
FORCEPROP 1 LASTPIN (8150 2125) $PN 1
J 0
(8160 2105);
DISPLAY 0.489362 (8160 2105);
FORCEPROP 1 LASTPIN (8150 1925) $PN 2
J 0
(8160 1905);
DISPLAY 0.489362 (8160 1905);
FORCEPROP 1 LAST MATERIAL X6S
J 0
(8200 1925);
DISPLAY 0.489362 (8200 1925);
PAINT SKYBLUE (8200 1925);
FORCEPROP 1 LAST TOLERANCE 20%
J 0
(8200 1975);
DISPLAY 0.489362 (8200 1975);
PAINT SKYBLUE (8200 1975);
FORCEPROP 1 LAST VALUE 22UF
J 0
(8200 2075);
DISPLAY 0.489362 (8200 2075);
PAINT SKYBLUE (8200 2075);
FORCEPROP 1 LAST PART_NUMBER CH622KMEB02
J 0
(8200 1875);
DISPLAY 0.489362 (8200 1875);
PAINT SKYBLUE (8200 1875);
FORCEPROP 1 LAST VOLTAGE 4V
J 0
(8200 2025);
DISPLAY 0.489362 (8200 2025);
PAINT SKYBLUE (8200 2025);
FORCEPROP 1 LAST PACK_TYPE C0402
J 0
(8200 1825);
DISPLAY 0.489362 (8200 1825);
PAINT SKYBLUE (8200 1825);
FORCEPROP 2 LAST CDS_LIB pure_quanta
J 0
(8150 2025);
PAINT MONO (8150 2025);
DISPLAY INVISIBLE (8150 2025);
FORCEPROP 1 LAST PATH I121
J 0
(8200 2175);
DISPLAY 0.978723 (8200 2175);
PAINT WHITE (8200 2175);
DISPLAY INVISIBLE (8200 2175);
FORCEADD Q_CAP..1
(8150 2650);
FORCEPROP 1 LAST LOCATION C2119
J 0
(8200 2750);
DISPLAY 0.489362 (8200 2750);
PAINT SKYBLUE (8200 2750);
FORCEPROP 2 LAST $SEC 1
J 0
(8200 2850);
DISPLAY 0.680851 (8200 2850);
PAINT MONO (8200 2850);
DISPLAY INVISIBLE (8200 2850);
FORCEPROP 2 LAST CDS_SEC 1
J 0
(8200 2850);
DISPLAY 1.021277 (8200 2850);
DISPLAY INVISIBLE (8200 2850);
FORCEPROP 1 LASTPIN (8150 2750) $PN 1
J 0
(8160 2730);
DISPLAY 0.489362 (8160 2730);
FORCEPROP 1 LASTPIN (8150 2550) $PN 2
J 0
(8160 2530);
DISPLAY 0.489362 (8160 2530);
FORCEPROP 1 LAST MATERIAL X6S
J 0
(8200 2550);
DISPLAY 0.489362 (8200 2550);
PAINT SKYBLUE (8200 2550);
FORCEPROP 1 LAST TOLERANCE 20%
J 0
(8200 2600);
DISPLAY 0.489362 (8200 2600);
PAINT SKYBLUE (8200 2600);
FORCEPROP 1 LAST VALUE 22UF
J 0
(8200 2700);
DISPLAY 0.489362 (8200 2700);
PAINT SKYBLUE (8200 2700);
FORCEPROP 1 LAST PART_NUMBER CH622KMEB02
J 0
(8200 2500);
DISPLAY 0.489362 (8200 2500);
PAINT SKYBLUE (8200 2500);
FORCEPROP 1 LAST VOLTAGE 4V
J 0
(8200 2650);
DISPLAY 0.489362 (8200 2650);
PAINT SKYBLUE (8200 2650);
FORCEPROP 1 LAST PACK_TYPE C0402
J 0
(8200 2450);
DISPLAY 0.489362 (8200 2450);
PAINT SKYBLUE (8200 2450);
FORCEPROP 2 LAST CDS_LIB pure_quanta
J 0
(8150 2650);
PAINT MONO (8150 2650);
DISPLAY INVISIBLE (8150 2650);
FORCEPROP 1 LAST PATH I122
J 0
(8200 2800);
DISPLAY 0.978723 (8200 2800);
PAINT WHITE (8200 2800);
DISPLAY INVISIBLE (8200 2800);
FORCEADD Q_CAP..1
(7250 3325);
FORCEPROP 1 LAST LOCATION C2503
J 0
(7300 3425);
DISPLAY 0.489362 (7300 3425);
PAINT SKYBLUE (7300 3425);
FORCEPROP 2 LAST $SEC 1
J 0
(7300 3525);
DISPLAY 0.680851 (7300 3525);
PAINT MONO (7300 3525);
DISPLAY INVISIBLE (7300 3525);
FORCEPROP 2 LAST CDS_SEC 1
J 0
(7300 3525);
DISPLAY 1.021277 (7300 3525);
DISPLAY INVISIBLE (7300 3525);
FORCEPROP 1 LASTPIN (7250 3425) $PN 1
J 0
(7260 3405);
DISPLAY 0.489362 (7260 3405);
FORCEPROP 1 LASTPIN (7250 3225) $PN 2
J 0
(7260 3205);
DISPLAY 0.489362 (7260 3205);
FORCEPROP 1 LAST MATERIAL X6S
J 0
(7300 3225);
DISPLAY 0.489362 (7300 3225);
PAINT SKYBLUE (7300 3225);
FORCEPROP 1 LAST TOLERANCE 20%
J 0
(7300 3275);
DISPLAY 0.489362 (7300 3275);
PAINT SKYBLUE (7300 3275);
FORCEPROP 1 LAST VALUE 22UF
J 0
(7300 3375);
DISPLAY 0.489362 (7300 3375);
PAINT SKYBLUE (7300 3375);
FORCEPROP 1 LAST PART_NUMBER CH622KMEB02
J 0
(7300 3175);
DISPLAY 0.489362 (7300 3175);
PAINT SKYBLUE (7300 3175);
FORCEPROP 1 LAST VOLTAGE 4V
J 0
(7300 3325);
DISPLAY 0.489362 (7300 3325);
PAINT SKYBLUE (7300 3325);
FORCEPROP 1 LAST PACK_TYPE C0402
J 0
(7300 3125);
DISPLAY 0.489362 (7300 3125);
PAINT SKYBLUE (7300 3125);
FORCEPROP 2 LAST CDS_LIB pure_quanta
J 0
(7250 3325);
PAINT MONO (7250 3325);
DISPLAY INVISIBLE (7250 3325);
FORCEPROP 1 LAST PATH I123
J 0
(7300 3475);
DISPLAY 0.978723 (7300 3475);
PAINT WHITE (7300 3475);
DISPLAY INVISIBLE (7300 3475);
FORCEADD Q_CAP..1
(7700 3325);
FORCEPROP 1 LAST LOCATION C2508
J 0
(7750 3425);
DISPLAY 0.489362 (7750 3425);
PAINT SKYBLUE (7750 3425);
FORCEPROP 2 LAST $SEC 1
J 0
(7750 3525);
DISPLAY 0.680851 (7750 3525);
PAINT MONO (7750 3525);
DISPLAY INVISIBLE (7750 3525);
FORCEPROP 2 LAST CDS_SEC 1
J 0
(7750 3525);
DISPLAY 1.021277 (7750 3525);
DISPLAY INVISIBLE (7750 3525);
FORCEPROP 1 LASTPIN (7700 3425) $PN 1
J 0
(7710 3405);
DISPLAY 0.489362 (7710 3405);
FORCEPROP 1 LASTPIN (7700 3225) $PN 2
J 0
(7710 3205);
DISPLAY 0.489362 (7710 3205);
FORCEPROP 1 LAST MATERIAL X6S
J 0
(7750 3225);
DISPLAY 0.489362 (7750 3225);
PAINT SKYBLUE (7750 3225);
FORCEPROP 1 LAST TOLERANCE 20%
J 0
(7750 3275);
DISPLAY 0.489362 (7750 3275);
PAINT SKYBLUE (7750 3275);
FORCEPROP 1 LAST VALUE 22UF
J 0
(7750 3375);
DISPLAY 0.489362 (7750 3375);
PAINT SKYBLUE (7750 3375);
FORCEPROP 1 LAST PART_NUMBER CH622KMEB02
J 0
(7750 3175);
DISPLAY 0.489362 (7750 3175);
PAINT SKYBLUE (7750 3175);
FORCEPROP 1 LAST VOLTAGE 4V
J 0
(7750 3325);
DISPLAY 0.489362 (7750 3325);
PAINT SKYBLUE (7750 3325);
FORCEPROP 1 LAST PACK_TYPE C0402
J 0
(7750 3125);
DISPLAY 0.489362 (7750 3125);
PAINT SKYBLUE (7750 3125);
FORCEPROP 2 LAST CDS_LIB pure_quanta
J 0
(7700 3325);
PAINT MONO (7700 3325);
DISPLAY INVISIBLE (7700 3325);
FORCEPROP 1 LAST PATH I124
J 0
(7750 3475);
DISPLAY 0.978723 (7750 3475);
PAINT WHITE (7750 3475);
DISPLAY INVISIBLE (7750 3475);
FORCEADD Q_CAP..1
(8150 3325);
FORCEPROP 1 LAST LOCATION C2118
J 0
(8200 3425);
DISPLAY 0.489362 (8200 3425);
PAINT SKYBLUE (8200 3425);
FORCEPROP 2 LAST $SEC 1
J 0
(8200 3525);
DISPLAY 0.680851 (8200 3525);
PAINT MONO (8200 3525);
DISPLAY INVISIBLE (8200 3525);
FORCEPROP 2 LAST CDS_SEC 1
J 0
(8200 3525);
DISPLAY 1.021277 (8200 3525);
DISPLAY INVISIBLE (8200 3525);
FORCEPROP 1 LASTPIN (8150 3425) $PN 1
J 0
(8160 3405);
DISPLAY 0.489362 (8160 3405);
FORCEPROP 1 LASTPIN (8150 3225) $PN 2
J 0
(8160 3205);
DISPLAY 0.489362 (8160 3205);
FORCEPROP 1 LAST MATERIAL X6S
J 0
(8200 3225);
DISPLAY 0.489362 (8200 3225);
PAINT SKYBLUE (8200 3225);
FORCEPROP 1 LAST TOLERANCE 20%
J 0
(8200 3275);
DISPLAY 0.489362 (8200 3275);
PAINT SKYBLUE (8200 3275);
FORCEPROP 1 LAST VALUE 22UF
J 0
(8200 3375);
DISPLAY 0.489362 (8200 3375);
PAINT SKYBLUE (8200 3375);
FORCEPROP 1 LAST PART_NUMBER CH622KMEB02
J 0
(8200 3175);
DISPLAY 0.489362 (8200 3175);
PAINT SKYBLUE (8200 3175);
FORCEPROP 1 LAST VOLTAGE 4V
J 0
(8200 3325);
DISPLAY 0.489362 (8200 3325);
PAINT SKYBLUE (8200 3325);
FORCEPROP 1 LAST PACK_TYPE C0402
J 0
(8200 3125);
DISPLAY 0.489362 (8200 3125);
PAINT SKYBLUE (8200 3125);
FORCEPROP 2 LAST CDS_LIB pure_quanta
J 0
(8150 3325);
PAINT MONO (8150 3325);
DISPLAY INVISIBLE (8150 3325);
FORCEPROP 1 LAST PATH I125
J 0
(8200 3475);
DISPLAY 0.978723 (8200 3475);
PAINT WHITE (8200 3475);
DISPLAY INVISIBLE (8200 3475);
FORCEADD UNIVERSAL_GND..1
(4400 4175);
FORCEPROP 3 LASTPIN (4400 4225) SIG_NAME GND\g
J 0
(4410 4235);
DISPLAY 0.659574 (4410 4235);
PAINT MONO (4410 4235);
DISPLAY INVISIBLE (4410 4235);
FORCEPROP 2 LAST CDS_LIB pure_quanta_power
J 0
(4400 4175);
PAINT MONO (4400 4175);
DISPLAY INVISIBLE (4400 4175);
FORCEPROP 1 LAST PATH I126
J 0
(4475 4175);
DISPLAY 0.872340 (4475 4175);
PAINT AQUA (4475 4175);
DISPLAY INVISIBLE (4475 4175);
FORCEPROP 1 LAST HDL_POWER GND
J 1
(4425 4100);
DISPLAY 0.872340 (4425 4100);
PAINT GREEN (4425 4100);
DISPLAY INVISIBLE (4425 4100);
FORCEADD Q_CAP..1
(4400 4550);
FORCEPROP 1 LAST LOCATION C2472
J 0
(4450 4650);
DISPLAY 0.489362 (4450 4650);
PAINT SKYBLUE (4450 4650);
FORCEPROP 2 LAST $SEC 1
J 0
(4450 4750);
DISPLAY 0.680851 (4450 4750);
PAINT MONO (4450 4750);
DISPLAY INVISIBLE (4450 4750);
FORCEPROP 2 LAST CDS_SEC 1
J 0
(4450 4750);
DISPLAY 1.021277 (4450 4750);
DISPLAY INVISIBLE (4450 4750);
FORCEPROP 1 LASTPIN (4400 4650) $PN 1
J 0
(4410 4630);
DISPLAY 0.489362 (4410 4630);
FORCEPROP 1 LASTPIN (4400 4450) $PN 2
J 0
(4410 4430);
DISPLAY 0.489362 (4410 4430);
FORCEPROP 1 LAST MATERIAL X6S
J 0
(4450 4450);
DISPLAY 0.489362 (4450 4450);
PAINT SKYBLUE (4450 4450);
FORCEPROP 1 LAST TOLERANCE 20%
J 0
(4450 4500);
DISPLAY 0.489362 (4450 4500);
PAINT SKYBLUE (4450 4500);
FORCEPROP 1 LAST VALUE 22UF
J 0
(4450 4600);
DISPLAY 0.489362 (4450 4600);
PAINT SKYBLUE (4450 4600);
FORCEPROP 1 LAST PART_NUMBER CH622KMEB02
J 0
(4450 4400);
DISPLAY 0.489362 (4450 4400);
PAINT SKYBLUE (4450 4400);
FORCEPROP 1 LAST VOLTAGE 4V
J 0
(4450 4550);
DISPLAY 0.489362 (4450 4550);
PAINT SKYBLUE (4450 4550);
FORCEPROP 1 LAST PACK_TYPE C0402
J 0
(4450 4350);
DISPLAY 0.489362 (4450 4350);
PAINT SKYBLUE (4450 4350);
FORCEPROP 2 LAST CDS_LIB pure_quanta
J 0
(4400 4550);
PAINT MONO (4400 4550);
DISPLAY INVISIBLE (4400 4550);
FORCEPROP 1 LAST PATH I127
J 0
(4450 4700);
DISPLAY 0.978723 (4450 4700);
PAINT WHITE (4450 4700);
DISPLAY INVISIBLE (4450 4700);
FORCEADD UNIVERSAL_GND..1
(4400 4850);
FORCEPROP 3 LASTPIN (4400 4900) SIG_NAME GND\g
J 0
(4410 4910);
DISPLAY 0.659574 (4410 4910);
PAINT MONO (4410 4910);
DISPLAY INVISIBLE (4410 4910);
FORCEPROP 2 LAST CDS_LIB pure_quanta_power
J 0
(4400 4850);
PAINT MONO (4400 4850);
DISPLAY INVISIBLE (4400 4850);
FORCEPROP 1 LAST PATH I128
J 0
(4475 4850);
DISPLAY 0.872340 (4475 4850);
PAINT AQUA (4475 4850);
DISPLAY INVISIBLE (4475 4850);
FORCEPROP 1 LAST HDL_POWER GND
J 1
(4425 4775);
DISPLAY 0.872340 (4425 4775);
PAINT GREEN (4425 4775);
DISPLAY INVISIBLE (4425 4775);
FORCEADD Q_CAP..1
(5000 4300);
FORCEPROP 1 LAST LOCATION C2479
J 0
(5050 4400);
DISPLAY 0.489362 (5050 4400);
PAINT SKYBLUE (5050 4400);
FORCEPROP 2 LAST $SEC 1
J 0
(5050 4500);
DISPLAY 0.680851 (5050 4500);
PAINT MONO (5050 4500);
DISPLAY INVISIBLE (5050 4500);
FORCEPROP 2 LAST CDS_SEC 1
J 0
(5050 4500);
DISPLAY 1.021277 (5050 4500);
DISPLAY INVISIBLE (5050 4500);
FORCEPROP 1 LASTPIN (5000 4400) $PN 1
J 0
(5010 4380);
DISPLAY 0.489362 (5010 4380);
FORCEPROP 1 LASTPIN (5000 4200) $PN 2
J 0
(5010 4180);
DISPLAY 0.489362 (5010 4180);
FORCEPROP 1 LAST MATERIAL X6S
J 0
(5050 4200);
DISPLAY 0.489362 (5050 4200);
PAINT SKYBLUE (5050 4200);
FORCEPROP 1 LAST TOLERANCE 20%
J 0
(5050 4250);
DISPLAY 0.489362 (5050 4250);
PAINT SKYBLUE (5050 4250);
FORCEPROP 1 LAST VALUE 22UF
J 0
(5050 4350);
DISPLAY 0.489362 (5050 4350);
PAINT SKYBLUE (5050 4350);
FORCEPROP 1 LAST PART_NUMBER CH622KMEB02
J 0
(5050 4150);
DISPLAY 0.489362 (5050 4150);
PAINT SKYBLUE (5050 4150);
FORCEPROP 1 LAST VOLTAGE 4V
J 0
(5050 4300);
DISPLAY 0.489362 (5050 4300);
PAINT SKYBLUE (5050 4300);
FORCEPROP 1 LAST PACK_TYPE C0402
J 0
(5050 4100);
DISPLAY 0.489362 (5050 4100);
PAINT SKYBLUE (5050 4100);
FORCEPROP 2 LAST CDS_LIB pure_quanta
J 0
(5000 4300);
PAINT MONO (5000 4300);
DISPLAY INVISIBLE (5000 4300);
FORCEPROP 1 LAST PATH I129
J 0
(5050 4450);
DISPLAY 0.978723 (5050 4450);
PAINT WHITE (5050 4450);
DISPLAY INVISIBLE (5050 4450);
FORCEADD Q_CAP..1
(850 2475);
FORCEPROP 1 LAST LOCATION C2419
J 0
(900 2575);
DISPLAY 0.489362 (900 2575);
PAINT SKYBLUE (900 2575);
FORCEPROP 2 LAST $SEC 1
J 0
(900 2675);
DISPLAY 0.680851 (900 2675);
PAINT MONO (900 2675);
DISPLAY INVISIBLE (900 2675);
FORCEPROP 2 LAST CDS_SEC 1
J 0
(900 2675);
DISPLAY 1.021277 (900 2675);
DISPLAY INVISIBLE (900 2675);
FORCEPROP 1 LASTPIN (850 2575) $PN 1
J 0
(860 2555);
DISPLAY 0.489362 (860 2555);
FORCEPROP 1 LASTPIN (850 2375) $PN 2
J 0
(860 2355);
DISPLAY 0.489362 (860 2355);
FORCEPROP 1 LAST MATERIAL X6S
J 0
(900 2375);
DISPLAY 0.489362 (900 2375);
PAINT SKYBLUE (900 2375);
FORCEPROP 1 LAST TOLERANCE 20%
J 0
(900 2425);
DISPLAY 0.489362 (900 2425);
PAINT SKYBLUE (900 2425);
FORCEPROP 1 LAST VALUE 22UF
J 0
(900 2525);
DISPLAY 0.489362 (900 2525);
PAINT SKYBLUE (900 2525);
FORCEPROP 1 LAST PART_NUMBER CH622KMEB02
J 0
(900 2325);
DISPLAY 0.489362 (900 2325);
PAINT SKYBLUE (900 2325);
FORCEPROP 1 LAST VOLTAGE 4V
J 0
(900 2475);
DISPLAY 0.489362 (900 2475);
PAINT SKYBLUE (900 2475);
FORCEPROP 1 LAST PACK_TYPE C0402
J 0
(900 2275);
DISPLAY 0.489362 (900 2275);
PAINT SKYBLUE (900 2275);
FORCEPROP 2 LAST CDS_LIB pure_quanta
J 0
(850 2475);
PAINT MONO (850 2475);
DISPLAY INVISIBLE (850 2475);
FORCEPROP 1 LAST PATH I13
J 0
(900 2625);
DISPLAY 0.978723 (900 2625);
PAINT WHITE (900 2625);
DISPLAY INVISIBLE (900 2625);
FORCEADD UNIVERSAL_POWER..1
(5000 4575);
FORCEPROP 3 LASTPIN (5000 4525) SIG_NAME PVDDIO_P1\g
J 0
(5010 4535);
DISPLAY 0.659574 (5010 4535);
PAINT MONO (5010 4535);
DISPLAY INVISIBLE (5010 4535);
FORCEPROP 1 LAST HDL_POWER PVDDIO_P1
J 1
(5000 4625);
DISPLAY 0.489362 (5000 4625);
PAINT GREEN (5000 4625);
FORCEPROP 2 LAST CDS_LIB pure_quanta_power
J 0
(5000 4575);
DISPLAY INVISIBLE (5000 4575);
FORCEPROP 1 LAST PATH I130
J 0
(5050 4600);
DISPLAY 0.872340 (5050 4600);
PAINT AQUA (5050 4600);
DISPLAY INVISIBLE (5050 4600);
FORCEADD Q_CAP..1
(4400 5225);
FORCEPROP 1 LAST LOCATION C2471
J 0
(4450 5325);
DISPLAY 0.489362 (4450 5325);
PAINT SKYBLUE (4450 5325);
FORCEPROP 2 LAST $SEC 1
J 0
(4450 5425);
DISPLAY 0.680851 (4450 5425);
PAINT MONO (4450 5425);
DISPLAY INVISIBLE (4450 5425);
FORCEPROP 2 LAST CDS_SEC 1
J 0
(4450 5425);
DISPLAY 1.021277 (4450 5425);
DISPLAY INVISIBLE (4450 5425);
FORCEPROP 1 LASTPIN (4400 5325) $PN 1
J 0
(4410 5305);
DISPLAY 0.489362 (4410 5305);
FORCEPROP 1 LASTPIN (4400 5125) $PN 2
J 0
(4410 5105);
DISPLAY 0.489362 (4410 5105);
FORCEPROP 1 LAST MATERIAL X6S
J 0
(4450 5125);
DISPLAY 0.489362 (4450 5125);
PAINT SKYBLUE (4450 5125);
FORCEPROP 1 LAST TOLERANCE 20%
J 0
(4450 5175);
DISPLAY 0.489362 (4450 5175);
PAINT SKYBLUE (4450 5175);
FORCEPROP 1 LAST VALUE 22UF
J 0
(4450 5275);
DISPLAY 0.489362 (4450 5275);
PAINT SKYBLUE (4450 5275);
FORCEPROP 1 LAST PART_NUMBER CH622KMEB02
J 0
(4450 5075);
DISPLAY 0.489362 (4450 5075);
PAINT SKYBLUE (4450 5075);
FORCEPROP 1 LAST VOLTAGE 4V
J 0
(4450 5225);
DISPLAY 0.489362 (4450 5225);
PAINT SKYBLUE (4450 5225);
FORCEPROP 1 LAST PACK_TYPE C0402
J 0
(4450 5025);
DISPLAY 0.489362 (4450 5025);
PAINT SKYBLUE (4450 5025);
FORCEPROP 2 LAST CDS_LIB pure_quanta
J 0
(4400 5225);
PAINT MONO (4400 5225);
DISPLAY INVISIBLE (4400 5225);
FORCEPROP 1 LAST PATH I131
J 0
(4450 5375);
DISPLAY 0.978723 (4450 5375);
PAINT WHITE (4450 5375);
DISPLAY INVISIBLE (4450 5375);
FORCEADD UNIVERSAL_GND..1
(4400 5500);
FORCEPROP 3 LASTPIN (4400 5550) SIG_NAME GND\g
J 0
(4410 5560);
DISPLAY 0.659574 (4410 5560);
PAINT MONO (4410 5560);
DISPLAY INVISIBLE (4410 5560);
FORCEPROP 2 LAST CDS_LIB pure_quanta_power
J 0
(4400 5500);
PAINT MONO (4400 5500);
DISPLAY INVISIBLE (4400 5500);
FORCEPROP 1 LAST PATH I132
J 0
(4475 5500);
DISPLAY 0.872340 (4475 5500);
PAINT AQUA (4475 5500);
DISPLAY INVISIBLE (4475 5500);
FORCEPROP 1 LAST HDL_POWER GND
J 1
(4425 5425);
DISPLAY 0.872340 (4425 5425);
PAINT GREEN (4425 5425);
DISPLAY INVISIBLE (4425 5425);
FORCEADD Q_CAP..1
(4400 5875);
FORCEPROP 1 LAST LOCATION C2470
J 0
(4450 5975);
DISPLAY 0.489362 (4450 5975);
PAINT SKYBLUE (4450 5975);
FORCEPROP 2 LAST $SEC 1
J 0
(4450 6075);
DISPLAY 0.680851 (4450 6075);
PAINT MONO (4450 6075);
DISPLAY INVISIBLE (4450 6075);
FORCEPROP 2 LAST CDS_SEC 1
J 0
(4450 6075);
DISPLAY 1.021277 (4450 6075);
DISPLAY INVISIBLE (4450 6075);
FORCEPROP 1 LASTPIN (4400 5975) $PN 1
J 0
(4410 5955);
DISPLAY 0.489362 (4410 5955);
FORCEPROP 1 LASTPIN (4400 5775) $PN 2
J 0
(4410 5755);
DISPLAY 0.489362 (4410 5755);
FORCEPROP 1 LAST MATERIAL X6S
J 0
(4450 5775);
DISPLAY 0.489362 (4450 5775);
PAINT SKYBLUE (4450 5775);
FORCEPROP 1 LAST TOLERANCE 20%
J 0
(4450 5825);
DISPLAY 0.489362 (4450 5825);
PAINT SKYBLUE (4450 5825);
FORCEPROP 1 LAST VALUE 22UF
J 0
(4450 5925);
DISPLAY 0.489362 (4450 5925);
PAINT SKYBLUE (4450 5925);
FORCEPROP 1 LAST PART_NUMBER CH622KMEB02
J 0
(4450 5725);
DISPLAY 0.489362 (4450 5725);
PAINT SKYBLUE (4450 5725);
FORCEPROP 1 LAST VOLTAGE 4V
J 0
(4450 5875);
DISPLAY 0.489362 (4450 5875);
PAINT SKYBLUE (4450 5875);
FORCEPROP 1 LAST PACK_TYPE C0402
J 0
(4450 5675);
DISPLAY 0.489362 (4450 5675);
PAINT SKYBLUE (4450 5675);
FORCEPROP 2 LAST CDS_LIB pure_quanta
J 0
(4400 5875);
PAINT MONO (4400 5875);
DISPLAY INVISIBLE (4400 5875);
FORCEPROP 1 LAST PATH I133
J 0
(4450 6025);
DISPLAY 0.978723 (4450 6025);
PAINT WHITE (4450 6025);
DISPLAY INVISIBLE (4450 6025);
FORCEADD Q_CAP..1
(4975 5075);
FORCEPROP 1 LAST LOCATION C2478
J 0
(5025 5175);
DISPLAY 0.489362 (5025 5175);
PAINT SKYBLUE (5025 5175);
FORCEPROP 2 LAST $SEC 1
J 0
(5025 5275);
DISPLAY 0.680851 (5025 5275);
PAINT MONO (5025 5275);
DISPLAY INVISIBLE (5025 5275);
FORCEPROP 2 LAST CDS_SEC 1
J 0
(5025 5275);
DISPLAY 1.021277 (5025 5275);
DISPLAY INVISIBLE (5025 5275);
FORCEPROP 1 LASTPIN (4975 5175) $PN 1
J 0
(4985 5155);
DISPLAY 0.489362 (4985 5155);
FORCEPROP 1 LASTPIN (4975 4975) $PN 2
J 0
(4985 4955);
DISPLAY 0.489362 (4985 4955);
FORCEPROP 1 LAST MATERIAL X6S
J 0
(5025 4975);
DISPLAY 0.489362 (5025 4975);
PAINT SKYBLUE (5025 4975);
FORCEPROP 1 LAST TOLERANCE 20%
J 0
(5025 5025);
DISPLAY 0.489362 (5025 5025);
PAINT SKYBLUE (5025 5025);
FORCEPROP 1 LAST VALUE 22UF
J 0
(5025 5125);
DISPLAY 0.489362 (5025 5125);
PAINT SKYBLUE (5025 5125);
FORCEPROP 1 LAST PART_NUMBER CH622KMEB02
J 0
(5025 4925);
DISPLAY 0.489362 (5025 4925);
PAINT SKYBLUE (5025 4925);
FORCEPROP 1 LAST VOLTAGE 4V
J 0
(5025 5075);
DISPLAY 0.489362 (5025 5075);
PAINT SKYBLUE (5025 5075);
FORCEPROP 1 LAST PACK_TYPE C0402
J 0
(5025 4875);
DISPLAY 0.489362 (5025 4875);
PAINT SKYBLUE (5025 4875);
FORCEPROP 2 LAST CDS_LIB pure_quanta
J 0
(4975 5075);
PAINT MONO (4975 5075);
DISPLAY INVISIBLE (4975 5075);
FORCEPROP 1 LAST PATH I134
J 0
(5025 5225);
DISPLAY 0.978723 (5025 5225);
PAINT WHITE (5025 5225);
DISPLAY INVISIBLE (5025 5225);
FORCEADD UNIVERSAL_POWER..1
(4975 5350);
FORCEPROP 3 LASTPIN (4975 5300) SIG_NAME PVDDIO_P1\g
J 0
(4985 5310);
DISPLAY 0.659574 (4985 5310);
PAINT MONO (4985 5310);
DISPLAY INVISIBLE (4985 5310);
FORCEPROP 1 LAST HDL_POWER PVDDIO_P1
J 1
(4975 5400);
DISPLAY 0.489362 (4975 5400);
PAINT GREEN (4975 5400);
FORCEPROP 2 LAST CDS_LIB pure_quanta_power
J 0
(4975 5350);
DISPLAY INVISIBLE (4975 5350);
FORCEPROP 1 LAST PATH I135
J 0
(5025 5375);
DISPLAY 0.872340 (5025 5375);
PAINT AQUA (5025 5375);
DISPLAY INVISIBLE (5025 5375);
FORCEADD Q_CAP..1
(4975 5875);
FORCEPROP 1 LAST LOCATION C2477
J 0
(5025 5975);
DISPLAY 0.489362 (5025 5975);
PAINT SKYBLUE (5025 5975);
FORCEPROP 2 LAST $SEC 1
J 0
(5025 6075);
DISPLAY 0.680851 (5025 6075);
PAINT MONO (5025 6075);
DISPLAY INVISIBLE (5025 6075);
FORCEPROP 2 LAST CDS_SEC 1
J 0
(5025 6075);
DISPLAY 1.021277 (5025 6075);
DISPLAY INVISIBLE (5025 6075);
FORCEPROP 1 LASTPIN (4975 5975) $PN 1
J 0
(4985 5955);
DISPLAY 0.489362 (4985 5955);
FORCEPROP 1 LASTPIN (4975 5775) $PN 2
J 0
(4985 5755);
DISPLAY 0.489362 (4985 5755);
FORCEPROP 1 LAST MATERIAL X6S
J 0
(5025 5775);
DISPLAY 0.489362 (5025 5775);
PAINT SKYBLUE (5025 5775);
FORCEPROP 1 LAST TOLERANCE 20%
J 0
(5025 5825);
DISPLAY 0.489362 (5025 5825);
PAINT SKYBLUE (5025 5825);
FORCEPROP 1 LAST VALUE 22UF
J 0
(5025 5925);
DISPLAY 0.489362 (5025 5925);
PAINT SKYBLUE (5025 5925);
FORCEPROP 1 LAST PART_NUMBER CH622KMEB02
J 0
(5025 5725);
DISPLAY 0.489362 (5025 5725);
PAINT SKYBLUE (5025 5725);
FORCEPROP 1 LAST VOLTAGE 4V
J 0
(5025 5875);
DISPLAY 0.489362 (5025 5875);
PAINT SKYBLUE (5025 5875);
FORCEPROP 1 LAST PACK_TYPE C0402
J 0
(5025 5675);
DISPLAY 0.489362 (5025 5675);
PAINT SKYBLUE (5025 5675);
FORCEPROP 2 LAST CDS_LIB pure_quanta
J 0
(4975 5875);
PAINT MONO (4975 5875);
DISPLAY INVISIBLE (4975 5875);
FORCEPROP 1 LAST PATH I136
J 0
(5025 6025);
DISPLAY 0.978723 (5025 6025);
PAINT WHITE (5025 6025);
DISPLAY INVISIBLE (5025 6025);
FORCEADD Q_CAP..1
(5450 4300);
FORCEPROP 1 LAST LOCATION C2103
J 0
(5500 4400);
DISPLAY 0.489362 (5500 4400);
PAINT SKYBLUE (5500 4400);
FORCEPROP 2 LAST $SEC 1
J 0
(5500 4500);
DISPLAY 0.680851 (5500 4500);
PAINT MONO (5500 4500);
DISPLAY INVISIBLE (5500 4500);
FORCEPROP 2 LAST CDS_SEC 1
J 0
(5500 4500);
DISPLAY 1.021277 (5500 4500);
DISPLAY INVISIBLE (5500 4500);
FORCEPROP 1 LASTPIN (5450 4400) $PN 1
J 0
(5460 4380);
DISPLAY 0.489362 (5460 4380);
FORCEPROP 1 LASTPIN (5450 4200) $PN 2
J 0
(5460 4180);
DISPLAY 0.489362 (5460 4180);
FORCEPROP 1 LAST MATERIAL X6S
J 0
(5500 4200);
DISPLAY 0.489362 (5500 4200);
PAINT SKYBLUE (5500 4200);
FORCEPROP 1 LAST TOLERANCE 20%
J 0
(5500 4250);
DISPLAY 0.489362 (5500 4250);
PAINT SKYBLUE (5500 4250);
FORCEPROP 1 LAST VALUE 22UF
J 0
(5500 4350);
DISPLAY 0.489362 (5500 4350);
PAINT SKYBLUE (5500 4350);
FORCEPROP 1 LAST PART_NUMBER CH622KMEB02
J 0
(5500 4150);
DISPLAY 0.489362 (5500 4150);
PAINT SKYBLUE (5500 4150);
FORCEPROP 1 LAST VOLTAGE 4V
J 0
(5500 4300);
DISPLAY 0.489362 (5500 4300);
PAINT SKYBLUE (5500 4300);
FORCEPROP 1 LAST PACK_TYPE C0402
J 0
(5500 4100);
DISPLAY 0.489362 (5500 4100);
PAINT SKYBLUE (5500 4100);
FORCEPROP 2 LAST CDS_LIB pure_quanta
J 0
(5450 4300);
PAINT MONO (5450 4300);
DISPLAY INVISIBLE (5450 4300);
FORCEPROP 1 LAST PATH I137
J 0
(5500 4450);
DISPLAY 0.978723 (5500 4450);
PAINT WHITE (5500 4450);
DISPLAY INVISIBLE (5500 4450);
FORCEADD Q_CAP..1
(5900 4300);
FORCEPROP 1 LAST LOCATION C2106
J 0
(5950 4400);
DISPLAY 0.489362 (5950 4400);
PAINT SKYBLUE (5950 4400);
FORCEPROP 2 LAST $SEC 1
J 0
(5950 4500);
DISPLAY 0.680851 (5950 4500);
PAINT MONO (5950 4500);
DISPLAY INVISIBLE (5950 4500);
FORCEPROP 2 LAST CDS_SEC 1
J 0
(5950 4500);
DISPLAY 1.021277 (5950 4500);
DISPLAY INVISIBLE (5950 4500);
FORCEPROP 1 LASTPIN (5900 4400) $PN 1
J 0
(5910 4380);
DISPLAY 0.489362 (5910 4380);
FORCEPROP 1 LASTPIN (5900 4200) $PN 2
J 0
(5910 4180);
DISPLAY 0.489362 (5910 4180);
FORCEPROP 1 LAST MATERIAL X6S
J 0
(5950 4200);
DISPLAY 0.489362 (5950 4200);
PAINT SKYBLUE (5950 4200);
FORCEPROP 1 LAST TOLERANCE 20%
J 0
(5950 4250);
DISPLAY 0.489362 (5950 4250);
PAINT SKYBLUE (5950 4250);
FORCEPROP 1 LAST VALUE 22UF
J 0
(5950 4350);
DISPLAY 0.489362 (5950 4350);
PAINT SKYBLUE (5950 4350);
FORCEPROP 1 LAST PART_NUMBER CH622KMEB02
J 0
(5950 4150);
DISPLAY 0.489362 (5950 4150);
PAINT SKYBLUE (5950 4150);
FORCEPROP 1 LAST VOLTAGE 4V
J 0
(5950 4300);
DISPLAY 0.489362 (5950 4300);
PAINT SKYBLUE (5950 4300);
FORCEPROP 1 LAST PACK_TYPE C0402
J 0
(5950 4100);
DISPLAY 0.489362 (5950 4100);
PAINT SKYBLUE (5950 4100);
FORCEPROP 2 LAST CDS_LIB pure_quanta
J 0
(5900 4300);
PAINT MONO (5900 4300);
DISPLAY INVISIBLE (5900 4300);
FORCEPROP 1 LAST PATH I138
J 0
(5950 4450);
DISPLAY 0.978723 (5950 4450);
PAINT WHITE (5950 4450);
DISPLAY INVISIBLE (5950 4450);
FORCEADD Q_CAP..1
(5425 5075);
FORCEPROP 1 LAST LOCATION C2484
J 0
(5475 5175);
DISPLAY 0.489362 (5475 5175);
PAINT SKYBLUE (5475 5175);
FORCEPROP 2 LAST $SEC 1
J 0
(5475 5275);
DISPLAY 0.680851 (5475 5275);
PAINT MONO (5475 5275);
DISPLAY INVISIBLE (5475 5275);
FORCEPROP 2 LAST CDS_SEC 1
J 0
(5475 5275);
DISPLAY 1.021277 (5475 5275);
DISPLAY INVISIBLE (5475 5275);
FORCEPROP 1 LASTPIN (5425 5175) $PN 1
J 0
(5435 5155);
DISPLAY 0.489362 (5435 5155);
FORCEPROP 1 LASTPIN (5425 4975) $PN 2
J 0
(5435 4955);
DISPLAY 0.489362 (5435 4955);
FORCEPROP 1 LAST MATERIAL X6S
J 0
(5475 4975);
DISPLAY 0.489362 (5475 4975);
PAINT SKYBLUE (5475 4975);
FORCEPROP 1 LAST TOLERANCE 20%
J 0
(5475 5025);
DISPLAY 0.489362 (5475 5025);
PAINT SKYBLUE (5475 5025);
FORCEPROP 1 LAST VALUE 22UF
J 0
(5475 5125);
DISPLAY 0.489362 (5475 5125);
PAINT SKYBLUE (5475 5125);
FORCEPROP 1 LAST PART_NUMBER CH622KMEB02
J 0
(5475 4925);
DISPLAY 0.489362 (5475 4925);
PAINT SKYBLUE (5475 4925);
FORCEPROP 1 LAST VOLTAGE 4V
J 0
(5475 5075);
DISPLAY 0.489362 (5475 5075);
PAINT SKYBLUE (5475 5075);
FORCEPROP 1 LAST PACK_TYPE C0402
J 0
(5475 4875);
DISPLAY 0.489362 (5475 4875);
PAINT SKYBLUE (5475 4875);
FORCEPROP 2 LAST CDS_LIB pure_quanta
J 0
(5425 5075);
PAINT MONO (5425 5075);
DISPLAY INVISIBLE (5425 5075);
FORCEPROP 1 LAST PATH I139
J 0
(5475 5225);
DISPLAY 0.978723 (5475 5225);
PAINT WHITE (5475 5225);
DISPLAY INVISIBLE (5475 5225);
FORCEADD Q_CAP..1
(400 3150);
FORCEPROP 1 LAST LOCATION C2411
J 0
(450 3250);
DISPLAY 0.489362 (450 3250);
PAINT SKYBLUE (450 3250);
FORCEPROP 2 LAST $SEC 1
J 0
(450 3350);
DISPLAY 0.680851 (450 3350);
PAINT MONO (450 3350);
DISPLAY INVISIBLE (450 3350);
FORCEPROP 2 LAST CDS_SEC 1
J 0
(450 3350);
DISPLAY 1.021277 (450 3350);
DISPLAY INVISIBLE (450 3350);
FORCEPROP 1 LASTPIN (400 3250) $PN 1
J 0
(410 3230);
DISPLAY 0.489362 (410 3230);
FORCEPROP 1 LASTPIN (400 3050) $PN 2
J 0
(410 3030);
DISPLAY 0.489362 (410 3030);
FORCEPROP 1 LAST MATERIAL X6S
J 0
(450 3050);
DISPLAY 0.489362 (450 3050);
PAINT SKYBLUE (450 3050);
FORCEPROP 1 LAST TOLERANCE 20%
J 0
(450 3100);
DISPLAY 0.489362 (450 3100);
PAINT SKYBLUE (450 3100);
FORCEPROP 1 LAST VALUE 22UF
J 0
(450 3200);
DISPLAY 0.489362 (450 3200);
PAINT SKYBLUE (450 3200);
FORCEPROP 1 LAST PART_NUMBER CH622KMEB02
J 0
(450 3000);
DISPLAY 0.489362 (450 3000);
PAINT SKYBLUE (450 3000);
FORCEPROP 1 LAST VOLTAGE 4V
J 0
(450 3150);
DISPLAY 0.489362 (450 3150);
PAINT SKYBLUE (450 3150);
FORCEPROP 1 LAST PACK_TYPE C0402
J 0
(450 2950);
DISPLAY 0.489362 (450 2950);
PAINT SKYBLUE (450 2950);
FORCEPROP 2 LAST CDS_LIB pure_quanta
J 0
(400 3150);
PAINT MONO (400 3150);
DISPLAY INVISIBLE (400 3150);
FORCEPROP 1 LAST PATH I14
J 0
(450 3300);
DISPLAY 0.978723 (450 3300);
PAINT WHITE (450 3300);
DISPLAY INVISIBLE (450 3300);
FORCEADD Q_CAP..1
(5425 5875);
FORCEPROP 1 LAST LOCATION C2102
J 0
(5475 5975);
DISPLAY 0.489362 (5475 5975);
PAINT SKYBLUE (5475 5975);
FORCEPROP 2 LAST $SEC 1
J 0
(5475 6075);
DISPLAY 0.680851 (5475 6075);
PAINT MONO (5475 6075);
DISPLAY INVISIBLE (5475 6075);
FORCEPROP 2 LAST CDS_SEC 1
J 0
(5475 6075);
DISPLAY 1.021277 (5475 6075);
DISPLAY INVISIBLE (5475 6075);
FORCEPROP 1 LASTPIN (5425 5975) $PN 1
J 0
(5435 5955);
DISPLAY 0.489362 (5435 5955);
FORCEPROP 1 LASTPIN (5425 5775) $PN 2
J 0
(5435 5755);
DISPLAY 0.489362 (5435 5755);
FORCEPROP 1 LAST MATERIAL X6S
J 0
(5475 5775);
DISPLAY 0.489362 (5475 5775);
PAINT SKYBLUE (5475 5775);
FORCEPROP 1 LAST TOLERANCE 20%
J 0
(5475 5825);
DISPLAY 0.489362 (5475 5825);
PAINT SKYBLUE (5475 5825);
FORCEPROP 1 LAST VALUE 22UF
J 0
(5475 5925);
DISPLAY 0.489362 (5475 5925);
PAINT SKYBLUE (5475 5925);
FORCEPROP 1 LAST PART_NUMBER CH622KMEB02
J 0
(5475 5725);
DISPLAY 0.489362 (5475 5725);
PAINT SKYBLUE (5475 5725);
FORCEPROP 1 LAST VOLTAGE 4V
J 0
(5475 5875);
DISPLAY 0.489362 (5475 5875);
PAINT SKYBLUE (5475 5875);
FORCEPROP 1 LAST PACK_TYPE C0402
J 0
(5475 5675);
DISPLAY 0.489362 (5475 5675);
PAINT SKYBLUE (5475 5675);
FORCEPROP 2 LAST CDS_LIB pure_quanta
J 0
(5425 5875);
PAINT MONO (5425 5875);
DISPLAY INVISIBLE (5425 5875);
FORCEPROP 1 LAST PATH I140
J 0
(5475 6025);
DISPLAY 0.978723 (5475 6025);
PAINT WHITE (5475 6025);
DISPLAY INVISIBLE (5475 6025);
FORCEADD Q_CAP..1
(5875 5075);
FORCEPROP 1 LAST LOCATION C2105
J 0
(5925 5175);
DISPLAY 0.489362 (5925 5175);
PAINT SKYBLUE (5925 5175);
FORCEPROP 2 LAST $SEC 1
J 0
(5925 5275);
DISPLAY 0.680851 (5925 5275);
PAINT MONO (5925 5275);
DISPLAY INVISIBLE (5925 5275);
FORCEPROP 2 LAST CDS_SEC 1
J 0
(5925 5275);
DISPLAY 1.021277 (5925 5275);
DISPLAY INVISIBLE (5925 5275);
FORCEPROP 1 LASTPIN (5875 5175) $PN 1
J 0
(5885 5155);
DISPLAY 0.489362 (5885 5155);
FORCEPROP 1 LASTPIN (5875 4975) $PN 2
J 0
(5885 4955);
DISPLAY 0.489362 (5885 4955);
FORCEPROP 1 LAST MATERIAL X6S
J 0
(5925 4975);
DISPLAY 0.489362 (5925 4975);
PAINT SKYBLUE (5925 4975);
FORCEPROP 1 LAST TOLERANCE 20%
J 0
(5925 5025);
DISPLAY 0.489362 (5925 5025);
PAINT SKYBLUE (5925 5025);
FORCEPROP 1 LAST VALUE 22UF
J 0
(5925 5125);
DISPLAY 0.489362 (5925 5125);
PAINT SKYBLUE (5925 5125);
FORCEPROP 1 LAST PART_NUMBER CH622KMEB02
J 0
(5925 4925);
DISPLAY 0.489362 (5925 4925);
PAINT SKYBLUE (5925 4925);
FORCEPROP 1 LAST VOLTAGE 4V
J 0
(5925 5075);
DISPLAY 0.489362 (5925 5075);
PAINT SKYBLUE (5925 5075);
FORCEPROP 1 LAST PACK_TYPE C0402
J 0
(5925 4875);
DISPLAY 0.489362 (5925 4875);
PAINT SKYBLUE (5925 4875);
FORCEPROP 2 LAST CDS_LIB pure_quanta
J 0
(5875 5075);
PAINT MONO (5875 5075);
DISPLAY INVISIBLE (5875 5075);
FORCEPROP 1 LAST PATH I141
J 0
(5925 5225);
DISPLAY 0.978723 (5925 5225);
PAINT WHITE (5925 5225);
DISPLAY INVISIBLE (5925 5225);
FORCEADD Q_CAP..1
(5875 5875);
FORCEPROP 1 LAST LOCATION C2104
J 0
(5925 5975);
DISPLAY 0.489362 (5925 5975);
PAINT SKYBLUE (5925 5975);
FORCEPROP 2 LAST $SEC 1
J 0
(5925 6075);
DISPLAY 0.680851 (5925 6075);
PAINT MONO (5925 6075);
DISPLAY INVISIBLE (5925 6075);
FORCEPROP 2 LAST CDS_SEC 1
J 0
(5925 6075);
DISPLAY 1.021277 (5925 6075);
DISPLAY INVISIBLE (5925 6075);
FORCEPROP 1 LASTPIN (5875 5975) $PN 1
J 0
(5885 5955);
DISPLAY 0.489362 (5885 5955);
FORCEPROP 1 LASTPIN (5875 5775) $PN 2
J 0
(5885 5755);
DISPLAY 0.489362 (5885 5755);
FORCEPROP 1 LAST MATERIAL X6S
J 0
(5925 5775);
DISPLAY 0.489362 (5925 5775);
PAINT SKYBLUE (5925 5775);
FORCEPROP 1 LAST TOLERANCE 20%
J 0
(5925 5825);
DISPLAY 0.489362 (5925 5825);
PAINT SKYBLUE (5925 5825);
FORCEPROP 1 LAST VALUE 22UF
J 0
(5925 5925);
DISPLAY 0.489362 (5925 5925);
PAINT SKYBLUE (5925 5925);
FORCEPROP 1 LAST PART_NUMBER CH622KMEB02
J 0
(5925 5725);
DISPLAY 0.489362 (5925 5725);
PAINT SKYBLUE (5925 5725);
FORCEPROP 1 LAST VOLTAGE 4V
J 0
(5925 5875);
DISPLAY 0.489362 (5925 5875);
PAINT SKYBLUE (5925 5875);
FORCEPROP 1 LAST PACK_TYPE C0402
J 0
(5925 5675);
DISPLAY 0.489362 (5925 5675);
PAINT SKYBLUE (5925 5675);
FORCEPROP 2 LAST CDS_LIB pure_quanta
J 0
(5875 5875);
PAINT MONO (5875 5875);
DISPLAY INVISIBLE (5875 5875);
FORCEPROP 1 LAST PATH I142
J 0
(5925 6025);
DISPLAY 0.978723 (5925 6025);
PAINT WHITE (5925 6025);
DISPLAY INVISIBLE (5925 6025);
FORCEADD UNIVERSAL_POWER..1
(4975 6150);
FORCEPROP 3 LASTPIN (4975 6100) SIG_NAME PVDDIO_P1\g
J 0
(4985 6110);
DISPLAY 0.659574 (4985 6110);
PAINT MONO (4985 6110);
DISPLAY INVISIBLE (4985 6110);
FORCEPROP 1 LAST HDL_POWER PVDDIO_P1
J 1
(4975 6200);
DISPLAY 0.489362 (4975 6200);
PAINT GREEN (4975 6200);
FORCEPROP 2 LAST CDS_LIB pure_quanta_power
J 0
(4975 6150);
DISPLAY INVISIBLE (4975 6150);
FORCEPROP 1 LAST PATH I143
J 0
(5025 6175);
DISPLAY 0.872340 (5025 6175);
PAINT AQUA (5025 6175);
DISPLAY INVISIBLE (5025 6175);
FORCEADD Q_CAP..1
(6350 4300);
FORCEPROP 1 LAST LOCATION C2108
J 0
(6400 4400);
DISPLAY 0.489362 (6400 4400);
PAINT SKYBLUE (6400 4400);
FORCEPROP 2 LAST $SEC 1
J 0
(6400 4500);
DISPLAY 0.680851 (6400 4500);
PAINT MONO (6400 4500);
DISPLAY INVISIBLE (6400 4500);
FORCEPROP 2 LAST CDS_SEC 1
J 0
(6400 4500);
DISPLAY 1.021277 (6400 4500);
DISPLAY INVISIBLE (6400 4500);
FORCEPROP 1 LASTPIN (6350 4400) $PN 1
J 0
(6360 4380);
DISPLAY 0.489362 (6360 4380);
FORCEPROP 1 LASTPIN (6350 4200) $PN 2
J 0
(6360 4180);
DISPLAY 0.489362 (6360 4180);
FORCEPROP 1 LAST MATERIAL X6S
J 0
(6400 4200);
DISPLAY 0.489362 (6400 4200);
PAINT SKYBLUE (6400 4200);
FORCEPROP 1 LAST TOLERANCE 20%
J 0
(6400 4250);
DISPLAY 0.489362 (6400 4250);
PAINT SKYBLUE (6400 4250);
FORCEPROP 1 LAST VALUE 22UF
J 0
(6400 4350);
DISPLAY 0.489362 (6400 4350);
PAINT SKYBLUE (6400 4350);
FORCEPROP 1 LAST PART_NUMBER CH622KMEB02
J 0
(6400 4150);
DISPLAY 0.489362 (6400 4150);
PAINT SKYBLUE (6400 4150);
FORCEPROP 1 LAST VOLTAGE 4V
J 0
(6400 4300);
DISPLAY 0.489362 (6400 4300);
PAINT SKYBLUE (6400 4300);
FORCEPROP 1 LAST PACK_TYPE C0402
J 0
(6400 4100);
DISPLAY 0.489362 (6400 4100);
PAINT SKYBLUE (6400 4100);
FORCEPROP 2 LAST CDS_LIB pure_quanta
J 0
(6350 4300);
PAINT MONO (6350 4300);
DISPLAY INVISIBLE (6350 4300);
FORCEPROP 1 LAST PATH I144
J 0
(6400 4450);
DISPLAY 0.978723 (6400 4450);
PAINT WHITE (6400 4450);
DISPLAY INVISIBLE (6400 4450);
FORCEADD Q_CAP..1
(6325 5075);
FORCEPROP 1 LAST LOCATION C2107
J 0
(6375 5175);
DISPLAY 0.489362 (6375 5175);
PAINT SKYBLUE (6375 5175);
FORCEPROP 2 LAST $SEC 1
J 0
(6375 5275);
DISPLAY 0.680851 (6375 5275);
PAINT MONO (6375 5275);
DISPLAY INVISIBLE (6375 5275);
FORCEPROP 2 LAST CDS_SEC 1
J 0
(6375 5275);
DISPLAY 1.021277 (6375 5275);
DISPLAY INVISIBLE (6375 5275);
FORCEPROP 1 LASTPIN (6325 5175) $PN 1
J 0
(6335 5155);
DISPLAY 0.489362 (6335 5155);
FORCEPROP 1 LASTPIN (6325 4975) $PN 2
J 0
(6335 4955);
DISPLAY 0.489362 (6335 4955);
FORCEPROP 1 LAST MATERIAL X6S
J 0
(6375 4975);
DISPLAY 0.489362 (6375 4975);
PAINT SKYBLUE (6375 4975);
FORCEPROP 1 LAST TOLERANCE 20%
J 0
(6375 5025);
DISPLAY 0.489362 (6375 5025);
PAINT SKYBLUE (6375 5025);
FORCEPROP 1 LAST VALUE 22UF
J 0
(6375 5125);
DISPLAY 0.489362 (6375 5125);
PAINT SKYBLUE (6375 5125);
FORCEPROP 1 LAST PART_NUMBER CH622KMEB02
J 0
(6375 4925);
DISPLAY 0.489362 (6375 4925);
PAINT SKYBLUE (6375 4925);
FORCEPROP 1 LAST VOLTAGE 4V
J 0
(6375 5075);
DISPLAY 0.489362 (6375 5075);
PAINT SKYBLUE (6375 5075);
FORCEPROP 1 LAST PACK_TYPE C0402
J 0
(6375 4875);
DISPLAY 0.489362 (6375 4875);
PAINT SKYBLUE (6375 4875);
FORCEPROP 2 LAST CDS_LIB pure_quanta
J 0
(6325 5075);
PAINT MONO (6325 5075);
DISPLAY INVISIBLE (6325 5075);
FORCEPROP 1 LAST PATH I145
J 0
(6375 5225);
DISPLAY 0.978723 (6375 5225);
PAINT WHITE (6375 5225);
DISPLAY INVISIBLE (6375 5225);
FORCEADD Q_CAP..1
(6325 5875);
FORCEPROP 1 LAST LOCATION C2493
J 0
(6375 5975);
DISPLAY 0.489362 (6375 5975);
PAINT SKYBLUE (6375 5975);
FORCEPROP 2 LAST $SEC 1
J 0
(6375 6075);
DISPLAY 0.680851 (6375 6075);
PAINT MONO (6375 6075);
DISPLAY INVISIBLE (6375 6075);
FORCEPROP 2 LAST CDS_SEC 1
J 0
(6375 6075);
DISPLAY 1.021277 (6375 6075);
DISPLAY INVISIBLE (6375 6075);
FORCEPROP 1 LASTPIN (6325 5975) $PN 1
J 0
(6335 5955);
DISPLAY 0.489362 (6335 5955);
FORCEPROP 1 LASTPIN (6325 5775) $PN 2
J 0
(6335 5755);
DISPLAY 0.489362 (6335 5755);
FORCEPROP 1 LAST MATERIAL X6S
J 0
(6375 5775);
DISPLAY 0.489362 (6375 5775);
PAINT SKYBLUE (6375 5775);
FORCEPROP 1 LAST TOLERANCE 20%
J 0
(6375 5825);
DISPLAY 0.489362 (6375 5825);
PAINT SKYBLUE (6375 5825);
FORCEPROP 1 LAST VALUE 22UF
J 0
(6375 5925);
DISPLAY 0.489362 (6375 5925);
PAINT SKYBLUE (6375 5925);
FORCEPROP 1 LAST PART_NUMBER CH622KMEB02
J 0
(6375 5725);
DISPLAY 0.489362 (6375 5725);
PAINT SKYBLUE (6375 5725);
FORCEPROP 1 LAST VOLTAGE 4V
J 0
(6375 5875);
DISPLAY 0.489362 (6375 5875);
PAINT SKYBLUE (6375 5875);
FORCEPROP 1 LAST PACK_TYPE C0402
J 0
(6375 5675);
DISPLAY 0.489362 (6375 5675);
PAINT SKYBLUE (6375 5675);
FORCEPROP 2 LAST CDS_LIB pure_quanta
J 0
(6325 5875);
PAINT MONO (6325 5875);
DISPLAY INVISIBLE (6325 5875);
FORCEPROP 1 LAST PATH I146
J 0
(6375 6025);
DISPLAY 0.978723 (6375 6025);
PAINT WHITE (6375 6025);
DISPLAY INVISIBLE (6375 6025);
FORCEADD Q_CAP..1
(6775 5075);
FORCEPROP 1 LAST LOCATION C2498
J 0
(6825 5175);
DISPLAY 0.489362 (6825 5175);
PAINT SKYBLUE (6825 5175);
FORCEPROP 2 LAST $SEC 1
J 0
(6825 5275);
DISPLAY 0.680851 (6825 5275);
PAINT MONO (6825 5275);
DISPLAY INVISIBLE (6825 5275);
FORCEPROP 2 LAST CDS_SEC 1
J 0
(6825 5275);
DISPLAY 1.021277 (6825 5275);
DISPLAY INVISIBLE (6825 5275);
FORCEPROP 1 LASTPIN (6775 5175) $PN 1
J 0
(6785 5155);
DISPLAY 0.489362 (6785 5155);
FORCEPROP 1 LASTPIN (6775 4975) $PN 2
J 0
(6785 4955);
DISPLAY 0.489362 (6785 4955);
FORCEPROP 1 LAST MATERIAL X6S
J 0
(6825 4975);
DISPLAY 0.489362 (6825 4975);
PAINT SKYBLUE (6825 4975);
FORCEPROP 1 LAST TOLERANCE 20%
J 0
(6825 5025);
DISPLAY 0.489362 (6825 5025);
PAINT SKYBLUE (6825 5025);
FORCEPROP 1 LAST VALUE 22UF
J 0
(6825 5125);
DISPLAY 0.489362 (6825 5125);
PAINT SKYBLUE (6825 5125);
FORCEPROP 1 LAST PART_NUMBER CH622KMEB02
J 0
(6825 4925);
DISPLAY 0.489362 (6825 4925);
PAINT SKYBLUE (6825 4925);
FORCEPROP 1 LAST VOLTAGE 4V
J 0
(6825 5075);
DISPLAY 0.489362 (6825 5075);
PAINT SKYBLUE (6825 5075);
FORCEPROP 1 LAST PACK_TYPE C0402
J 0
(6825 4875);
DISPLAY 0.489362 (6825 4875);
PAINT SKYBLUE (6825 4875);
FORCEPROP 2 LAST CDS_LIB pure_quanta
J 0
(6775 5075);
PAINT MONO (6775 5075);
DISPLAY INVISIBLE (6775 5075);
FORCEPROP 1 LAST PATH I147
J 0
(6825 5225);
DISPLAY 0.978723 (6825 5225);
PAINT WHITE (6825 5225);
DISPLAY INVISIBLE (6825 5225);
FORCEADD Q_CAP..1
(6775 5875);
FORCEPROP 1 LAST LOCATION C2109
J 0
(6825 5975);
DISPLAY 0.489362 (6825 5975);
PAINT SKYBLUE (6825 5975);
FORCEPROP 2 LAST $SEC 1
J 0
(6825 6075);
DISPLAY 0.680851 (6825 6075);
PAINT MONO (6825 6075);
DISPLAY INVISIBLE (6825 6075);
FORCEPROP 2 LAST CDS_SEC 1
J 0
(6825 6075);
DISPLAY 1.021277 (6825 6075);
DISPLAY INVISIBLE (6825 6075);
FORCEPROP 1 LASTPIN (6775 5975) $PN 1
J 0
(6785 5955);
DISPLAY 0.489362 (6785 5955);
FORCEPROP 1 LASTPIN (6775 5775) $PN 2
J 0
(6785 5755);
DISPLAY 0.489362 (6785 5755);
FORCEPROP 1 LAST MATERIAL X6S
J 0
(6825 5775);
DISPLAY 0.489362 (6825 5775);
PAINT SKYBLUE (6825 5775);
FORCEPROP 1 LAST TOLERANCE 20%
J 0
(6825 5825);
DISPLAY 0.489362 (6825 5825);
PAINT SKYBLUE (6825 5825);
FORCEPROP 1 LAST VALUE 22UF
J 0
(6825 5925);
DISPLAY 0.489362 (6825 5925);
PAINT SKYBLUE (6825 5925);
FORCEPROP 1 LAST PART_NUMBER CH622KMEB02
J 0
(6825 5725);
DISPLAY 0.489362 (6825 5725);
PAINT SKYBLUE (6825 5725);
FORCEPROP 1 LAST VOLTAGE 4V
J 0
(6825 5875);
DISPLAY 0.489362 (6825 5875);
PAINT SKYBLUE (6825 5875);
FORCEPROP 1 LAST PACK_TYPE C0402
J 0
(6825 5675);
DISPLAY 0.489362 (6825 5675);
PAINT SKYBLUE (6825 5675);
FORCEPROP 2 LAST CDS_LIB pure_quanta
J 0
(6775 5875);
PAINT MONO (6775 5875);
DISPLAY INVISIBLE (6775 5875);
FORCEPROP 1 LAST PATH I148
J 0
(6825 6025);
DISPLAY 0.978723 (6825 6025);
PAINT WHITE (6825 6025);
DISPLAY INVISIBLE (6825 6025);
FORCEADD Q_CAP..1
(7225 5075);
FORCEPROP 1 LAST LOCATION C2111
J 0
(7275 5175);
DISPLAY 0.489362 (7275 5175);
PAINT SKYBLUE (7275 5175);
FORCEPROP 2 LAST $SEC 1
J 0
(7275 5275);
DISPLAY 0.680851 (7275 5275);
PAINT MONO (7275 5275);
DISPLAY INVISIBLE (7275 5275);
FORCEPROP 2 LAST CDS_SEC 1
J 0
(7275 5275);
DISPLAY 1.021277 (7275 5275);
DISPLAY INVISIBLE (7275 5275);
FORCEPROP 1 LASTPIN (7225 5175) $PN 1
J 0
(7235 5155);
DISPLAY 0.489362 (7235 5155);
FORCEPROP 1 LASTPIN (7225 4975) $PN 2
J 0
(7235 4955);
DISPLAY 0.489362 (7235 4955);
FORCEPROP 1 LAST MATERIAL X6S
J 0
(7275 4975);
DISPLAY 0.489362 (7275 4975);
PAINT SKYBLUE (7275 4975);
FORCEPROP 1 LAST TOLERANCE 20%
J 0
(7275 5025);
DISPLAY 0.489362 (7275 5025);
PAINT SKYBLUE (7275 5025);
FORCEPROP 1 LAST VALUE 22UF
J 0
(7275 5125);
DISPLAY 0.489362 (7275 5125);
PAINT SKYBLUE (7275 5125);
FORCEPROP 1 LAST PART_NUMBER CH622KMEB02
J 0
(7275 4925);
DISPLAY 0.489362 (7275 4925);
PAINT SKYBLUE (7275 4925);
FORCEPROP 1 LAST VOLTAGE 4V
J 0
(7275 5075);
DISPLAY 0.489362 (7275 5075);
PAINT SKYBLUE (7275 5075);
FORCEPROP 1 LAST PACK_TYPE C0402
J 0
(7275 4875);
DISPLAY 0.489362 (7275 4875);
PAINT SKYBLUE (7275 4875);
FORCEPROP 2 LAST CDS_LIB pure_quanta
J 0
(7225 5075);
PAINT MONO (7225 5075);
DISPLAY INVISIBLE (7225 5075);
FORCEPROP 1 LAST PATH I149
J 0
(7275 5225);
DISPLAY 0.978723 (7275 5225);
PAINT WHITE (7275 5225);
DISPLAY INVISIBLE (7275 5225);
FORCEADD UNIVERSAL_POWER..1
(400 3425);
FORCEPROP 3 LASTPIN (400 3375) SIG_NAME PVDDCR_SOC_P1\g
J 0
(410 3385);
DISPLAY 0.659574 (410 3385);
PAINT MONO (410 3385);
DISPLAY INVISIBLE (410 3385);
FORCEPROP 1 LAST HDL_POWER PVDDCR_SOC_P1
J 1
(400 3475);
DISPLAY 0.489362 (400 3475);
PAINT GREEN (400 3475);
FORCEPROP 2 LAST CDS_LIB pure_quanta_power
J 0
(400 3425);
DISPLAY INVISIBLE (400 3425);
FORCEPROP 1 LAST PATH I15
J 0
(450 3450);
DISPLAY 0.872340 (450 3450);
PAINT AQUA (450 3450);
DISPLAY INVISIBLE (450 3450);
FORCEADD Q_CAP..1
(7675 5075);
FORCEPROP 1 LAST LOCATION C2112
J 0
(7725 5175);
DISPLAY 0.489362 (7725 5175);
PAINT SKYBLUE (7725 5175);
FORCEPROP 2 LAST $SEC 1
J 0
(7725 5275);
DISPLAY 0.680851 (7725 5275);
PAINT MONO (7725 5275);
DISPLAY INVISIBLE (7725 5275);
FORCEPROP 2 LAST CDS_SEC 1
J 0
(7725 5275);
DISPLAY 1.021277 (7725 5275);
DISPLAY INVISIBLE (7725 5275);
FORCEPROP 1 LASTPIN (7675 5175) $PN 1
J 0
(7685 5155);
DISPLAY 0.489362 (7685 5155);
FORCEPROP 1 LASTPIN (7675 4975) $PN 2
J 0
(7685 4955);
DISPLAY 0.489362 (7685 4955);
FORCEPROP 1 LAST MATERIAL X6S
J 0
(7725 4975);
DISPLAY 0.489362 (7725 4975);
PAINT SKYBLUE (7725 4975);
FORCEPROP 1 LAST TOLERANCE 20%
J 0
(7725 5025);
DISPLAY 0.489362 (7725 5025);
PAINT SKYBLUE (7725 5025);
FORCEPROP 1 LAST VALUE 22UF
J 0
(7725 5125);
DISPLAY 0.489362 (7725 5125);
PAINT SKYBLUE (7725 5125);
FORCEPROP 1 LAST PART_NUMBER CH622KMEB02
J 0
(7725 4925);
DISPLAY 0.489362 (7725 4925);
PAINT SKYBLUE (7725 4925);
FORCEPROP 1 LAST VOLTAGE 4V
J 0
(7725 5075);
DISPLAY 0.489362 (7725 5075);
PAINT SKYBLUE (7725 5075);
FORCEPROP 1 LAST PACK_TYPE C0402
J 0
(7725 4875);
DISPLAY 0.489362 (7725 4875);
PAINT SKYBLUE (7725 4875);
FORCEPROP 2 LAST CDS_LIB pure_quanta
J 0
(7675 5075);
PAINT MONO (7675 5075);
DISPLAY INVISIBLE (7675 5075);
FORCEPROP 1 LAST PATH I150
J 0
(7725 5225);
DISPLAY 0.978723 (7725 5225);
PAINT WHITE (7725 5225);
DISPLAY INVISIBLE (7725 5225);
FORCEADD Q_CAP..1
(7225 5875);
FORCEPROP 1 LAST LOCATION C2110
J 0
(7275 5975);
DISPLAY 0.489362 (7275 5975);
PAINT SKYBLUE (7275 5975);
FORCEPROP 2 LAST $SEC 1
J 0
(7275 6075);
DISPLAY 0.680851 (7275 6075);
PAINT MONO (7275 6075);
DISPLAY INVISIBLE (7275 6075);
FORCEPROP 2 LAST CDS_SEC 1
J 0
(7275 6075);
DISPLAY 1.021277 (7275 6075);
DISPLAY INVISIBLE (7275 6075);
FORCEPROP 1 LASTPIN (7225 5975) $PN 1
J 0
(7235 5955);
DISPLAY 0.489362 (7235 5955);
FORCEPROP 1 LASTPIN (7225 5775) $PN 2
J 0
(7235 5755);
DISPLAY 0.489362 (7235 5755);
FORCEPROP 1 LAST MATERIAL X6S
J 0
(7275 5775);
DISPLAY 0.489362 (7275 5775);
PAINT SKYBLUE (7275 5775);
FORCEPROP 1 LAST TOLERANCE 20%
J 0
(7275 5825);
DISPLAY 0.489362 (7275 5825);
PAINT SKYBLUE (7275 5825);
FORCEPROP 1 LAST VALUE 22UF
J 0
(7275 5925);
DISPLAY 0.489362 (7275 5925);
PAINT SKYBLUE (7275 5925);
FORCEPROP 1 LAST PART_NUMBER CH622KMEB02
J 0
(7275 5725);
DISPLAY 0.489362 (7275 5725);
PAINT SKYBLUE (7275 5725);
FORCEPROP 1 LAST VOLTAGE 4V
J 0
(7275 5875);
DISPLAY 0.489362 (7275 5875);
PAINT SKYBLUE (7275 5875);
FORCEPROP 1 LAST PACK_TYPE C0402
J 0
(7275 5675);
DISPLAY 0.489362 (7275 5675);
PAINT SKYBLUE (7275 5675);
FORCEPROP 2 LAST CDS_LIB pure_quanta
J 0
(7225 5875);
PAINT MONO (7225 5875);
DISPLAY INVISIBLE (7225 5875);
FORCEPROP 1 LAST PATH I151
J 0
(7275 6025);
DISPLAY 0.978723 (7275 6025);
PAINT WHITE (7275 6025);
DISPLAY INVISIBLE (7275 6025);
FORCEADD Q_CAP..1
(7675 5875);
FORCEPROP 1 LAST LOCATION C2507
J 0
(7725 5975);
DISPLAY 0.489362 (7725 5975);
PAINT SKYBLUE (7725 5975);
FORCEPROP 2 LAST $SEC 1
J 0
(7725 6075);
DISPLAY 0.680851 (7725 6075);
PAINT MONO (7725 6075);
DISPLAY INVISIBLE (7725 6075);
FORCEPROP 2 LAST CDS_SEC 1
J 0
(7725 6075);
DISPLAY 1.021277 (7725 6075);
DISPLAY INVISIBLE (7725 6075);
FORCEPROP 1 LASTPIN (7675 5975) $PN 1
J 0
(7685 5955);
DISPLAY 0.489362 (7685 5955);
FORCEPROP 1 LASTPIN (7675 5775) $PN 2
J 0
(7685 5755);
DISPLAY 0.489362 (7685 5755);
FORCEPROP 1 LAST MATERIAL X6S
J 0
(7725 5775);
DISPLAY 0.489362 (7725 5775);
PAINT SKYBLUE (7725 5775);
FORCEPROP 1 LAST TOLERANCE 20%
J 0
(7725 5825);
DISPLAY 0.489362 (7725 5825);
PAINT SKYBLUE (7725 5825);
FORCEPROP 1 LAST VALUE 22UF
J 0
(7725 5925);
DISPLAY 0.489362 (7725 5925);
PAINT SKYBLUE (7725 5925);
FORCEPROP 1 LAST PART_NUMBER CH622KMEB02
J 0
(7725 5725);
DISPLAY 0.489362 (7725 5725);
PAINT SKYBLUE (7725 5725);
FORCEPROP 1 LAST VOLTAGE 4V
J 0
(7725 5875);
DISPLAY 0.489362 (7725 5875);
PAINT SKYBLUE (7725 5875);
FORCEPROP 1 LAST PACK_TYPE C0402
J 0
(7725 5675);
DISPLAY 0.489362 (7725 5675);
PAINT SKYBLUE (7725 5675);
FORCEPROP 2 LAST CDS_LIB pure_quanta
J 0
(7675 5875);
PAINT MONO (7675 5875);
DISPLAY INVISIBLE (7675 5875);
FORCEPROP 1 LAST PATH I152
J 0
(7725 6025);
DISPLAY 0.978723 (7725 6025);
PAINT WHITE (7725 6025);
DISPLAY INVISIBLE (7725 6025);
FORCEADD Q_CAP..1
(8125 5075);
FORCEPROP 1 LAST LOCATION C2117
J 0
(8175 5175);
DISPLAY 0.489362 (8175 5175);
PAINT SKYBLUE (8175 5175);
FORCEPROP 2 LAST $SEC 1
J 0
(8175 5275);
DISPLAY 0.680851 (8175 5275);
PAINT MONO (8175 5275);
DISPLAY INVISIBLE (8175 5275);
FORCEPROP 2 LAST CDS_SEC 1
J 0
(8175 5275);
DISPLAY 1.021277 (8175 5275);
DISPLAY INVISIBLE (8175 5275);
FORCEPROP 1 LASTPIN (8125 5175) $PN 1
J 0
(8135 5155);
DISPLAY 0.489362 (8135 5155);
FORCEPROP 1 LASTPIN (8125 4975) $PN 2
J 0
(8135 4955);
DISPLAY 0.489362 (8135 4955);
FORCEPROP 1 LAST MATERIAL X6S
J 0
(8175 4975);
DISPLAY 0.489362 (8175 4975);
PAINT SKYBLUE (8175 4975);
FORCEPROP 1 LAST TOLERANCE 20%
J 0
(8175 5025);
DISPLAY 0.489362 (8175 5025);
PAINT SKYBLUE (8175 5025);
FORCEPROP 1 LAST VALUE 22UF
J 0
(8175 5125);
DISPLAY 0.489362 (8175 5125);
PAINT SKYBLUE (8175 5125);
FORCEPROP 1 LAST PART_NUMBER CH622KMEB02
J 0
(8175 4925);
DISPLAY 0.489362 (8175 4925);
PAINT SKYBLUE (8175 4925);
FORCEPROP 1 LAST VOLTAGE 4V
J 0
(8175 5075);
DISPLAY 0.489362 (8175 5075);
PAINT SKYBLUE (8175 5075);
FORCEPROP 1 LAST PACK_TYPE C0402
J 0
(8175 4875);
DISPLAY 0.489362 (8175 4875);
PAINT SKYBLUE (8175 4875);
FORCEPROP 2 LAST CDS_LIB pure_quanta
J 0
(8125 5075);
PAINT MONO (8125 5075);
DISPLAY INVISIBLE (8125 5075);
FORCEPROP 1 LAST PATH I153
J 0
(8175 5225);
DISPLAY 0.978723 (8175 5225);
PAINT WHITE (8175 5225);
DISPLAY INVISIBLE (8175 5225);
FORCEADD Q_CAP..1
(8125 5875);
FORCEPROP 1 LAST LOCATION C2116
J 0
(8175 5975);
DISPLAY 0.489362 (8175 5975);
PAINT SKYBLUE (8175 5975);
FORCEPROP 2 LAST $SEC 1
J 0
(8175 6075);
DISPLAY 0.680851 (8175 6075);
PAINT MONO (8175 6075);
DISPLAY INVISIBLE (8175 6075);
FORCEPROP 2 LAST CDS_SEC 1
J 0
(8175 6075);
DISPLAY 1.021277 (8175 6075);
DISPLAY INVISIBLE (8175 6075);
FORCEPROP 1 LASTPIN (8125 5975) $PN 1
J 0
(8135 5955);
DISPLAY 0.489362 (8135 5955);
FORCEPROP 1 LASTPIN (8125 5775) $PN 2
J 0
(8135 5755);
DISPLAY 0.489362 (8135 5755);
FORCEPROP 1 LAST MATERIAL X6S
J 0
(8175 5775);
DISPLAY 0.489362 (8175 5775);
PAINT SKYBLUE (8175 5775);
FORCEPROP 1 LAST TOLERANCE 20%
J 0
(8175 5825);
DISPLAY 0.489362 (8175 5825);
PAINT SKYBLUE (8175 5825);
FORCEPROP 1 LAST VALUE 22UF
J 0
(8175 5925);
DISPLAY 0.489362 (8175 5925);
PAINT SKYBLUE (8175 5925);
FORCEPROP 1 LAST PART_NUMBER CH622KMEB02
J 0
(8175 5725);
DISPLAY 0.489362 (8175 5725);
PAINT SKYBLUE (8175 5725);
FORCEPROP 1 LAST VOLTAGE 4V
J 0
(8175 5875);
DISPLAY 0.489362 (8175 5875);
PAINT SKYBLUE (8175 5875);
FORCEPROP 1 LAST PACK_TYPE C0402
J 0
(8175 5675);
DISPLAY 0.489362 (8175 5675);
PAINT SKYBLUE (8175 5675);
FORCEPROP 2 LAST CDS_LIB pure_quanta
J 0
(8125 5875);
PAINT MONO (8125 5875);
DISPLAY INVISIBLE (8125 5875);
FORCEPROP 1 LAST PATH I154
J 0
(8175 6025);
DISPLAY 0.978723 (8175 6025);
PAINT WHITE (8175 6025);
DISPLAY INVISIBLE (8175 6025);
FORCEADD Q_CAP..1
(8600 1375);
FORCEPROP 1 LAST LOCATION C3921
J 0
(8650 1475);
DISPLAY 0.489362 (8650 1475);
PAINT SKYBLUE (8650 1475);
FORCEPROP 2 LAST $SEC 1
J 0
(8650 1575);
DISPLAY 0.680851 (8650 1575);
PAINT MONO (8650 1575);
DISPLAY INVISIBLE (8650 1575);
FORCEPROP 2 LAST CDS_SEC 1
J 0
(8650 1575);
DISPLAY 1.021277 (8650 1575);
DISPLAY INVISIBLE (8650 1575);
FORCEPROP 1 LASTPIN (8600 1475) $PN 1
J 0
(8610 1455);
DISPLAY 0.489362 (8610 1455);
FORCEPROP 1 LASTPIN (8600 1275) $PN 2
J 0
(8610 1255);
DISPLAY 0.489362 (8610 1255);
FORCEPROP 1 LAST MATERIAL X6S
J 0
(8650 1275);
DISPLAY 0.489362 (8650 1275);
PAINT SKYBLUE (8650 1275);
FORCEPROP 1 LAST TOLERANCE 20%
J 0
(8650 1325);
DISPLAY 0.489362 (8650 1325);
PAINT SKYBLUE (8650 1325);
FORCEPROP 1 LAST VALUE 22UF
J 0
(8650 1425);
DISPLAY 0.489362 (8650 1425);
PAINT SKYBLUE (8650 1425);
FORCEPROP 1 LAST PART_NUMBER CH622KMEB02
J 0
(8650 1225);
DISPLAY 0.489362 (8650 1225);
PAINT SKYBLUE (8650 1225);
FORCEPROP 1 LAST VOLTAGE 4V
J 0
(8650 1375);
DISPLAY 0.489362 (8650 1375);
PAINT SKYBLUE (8650 1375);
FORCEPROP 1 LAST PACK_TYPE C0402
J 0
(8650 1175);
DISPLAY 0.489362 (8650 1175);
PAINT SKYBLUE (8650 1175);
FORCEPROP 2 LAST CDS_LIB pure_quanta
J 0
(8600 1375);
PAINT MONO (8600 1375);
DISPLAY INVISIBLE (8600 1375);
FORCEPROP 1 LAST PATH I155
J 0
(8650 1525);
DISPLAY 0.978723 (8650 1525);
PAINT WHITE (8650 1525);
DISPLAY INVISIBLE (8650 1525);
FORCEADD UNIVERSAL_GND..1
(9000 1000);
FORCEPROP 3 LASTPIN (9000 1050) SIG_NAME GND\g
J 0
(9010 1060);
DISPLAY 0.659574 (9010 1060);
PAINT MONO (9010 1060);
DISPLAY INVISIBLE (9010 1060);
FORCEPROP 2 LAST CDS_LIB pure_quanta_power
J 0
(9000 1000);
PAINT MONO (9000 1000);
DISPLAY INVISIBLE (9000 1000);
FORCEPROP 1 LAST PATH I156
J 0
(9075 1000);
DISPLAY 0.872340 (9075 1000);
PAINT AQUA (9075 1000);
DISPLAY INVISIBLE (9075 1000);
FORCEPROP 1 LAST HDL_POWER GND
J 1
(9025 925);
DISPLAY 0.872340 (9025 925);
PAINT GREEN (9025 925);
DISPLAY INVISIBLE (9025 925);
FORCEADD Q_CAP..1
(9000 1375);
FORCEPROP 1 LAST LOCATION C3922
J 0
(9050 1475);
DISPLAY 0.489362 (9050 1475);
PAINT SKYBLUE (9050 1475);
FORCEPROP 2 LAST $SEC 1
J 0
(9050 1575);
DISPLAY 0.680851 (9050 1575);
PAINT MONO (9050 1575);
DISPLAY INVISIBLE (9050 1575);
FORCEPROP 2 LAST CDS_SEC 1
J 0
(9050 1575);
DISPLAY 1.021277 (9050 1575);
DISPLAY INVISIBLE (9050 1575);
FORCEPROP 1 LASTPIN (9000 1475) $PN 1
J 0
(9010 1455);
DISPLAY 0.489362 (9010 1455);
FORCEPROP 1 LASTPIN (9000 1275) $PN 2
J 0
(9010 1255);
DISPLAY 0.489362 (9010 1255);
FORCEPROP 1 LAST MATERIAL X6S
J 0
(9050 1275);
DISPLAY 0.489362 (9050 1275);
PAINT SKYBLUE (9050 1275);
FORCEPROP 1 LAST TOLERANCE 20%
J 0
(9050 1325);
DISPLAY 0.489362 (9050 1325);
PAINT SKYBLUE (9050 1325);
FORCEPROP 1 LAST VALUE 22UF
J 0
(9050 1425);
DISPLAY 0.489362 (9050 1425);
PAINT SKYBLUE (9050 1425);
FORCEPROP 1 LAST PART_NUMBER CH622KMEB02
J 0
(9050 1225);
DISPLAY 0.489362 (9050 1225);
PAINT SKYBLUE (9050 1225);
FORCEPROP 1 LAST VOLTAGE 4V
J 0
(9050 1375);
DISPLAY 0.489362 (9050 1375);
PAINT SKYBLUE (9050 1375);
FORCEPROP 1 LAST PACK_TYPE C0402
J 0
(9050 1175);
DISPLAY 0.489362 (9050 1175);
PAINT SKYBLUE (9050 1175);
FORCEPROP 2 LAST CDS_LIB pure_quanta
J 0
(9000 1375);
PAINT MONO (9000 1375);
DISPLAY INVISIBLE (9000 1375);
FORCEPROP 1 LAST PATH I157
J 0
(9050 1525);
DISPLAY 0.978723 (9050 1525);
PAINT WHITE (9050 1525);
DISPLAY INVISIBLE (9050 1525);
FORCEADD UNIVERSAL_GND..1
(9000 1650);
FORCEPROP 3 LASTPIN (9000 1700) SIG_NAME GND\g
J 0
(9010 1710);
DISPLAY 0.659574 (9010 1710);
PAINT MONO (9010 1710);
DISPLAY INVISIBLE (9010 1710);
FORCEPROP 2 LAST CDS_LIB pure_quanta_power
J 0
(9000 1650);
PAINT MONO (9000 1650);
DISPLAY INVISIBLE (9000 1650);
FORCEPROP 1 LAST PATH I158
J 0
(9075 1650);
DISPLAY 0.872340 (9075 1650);
PAINT AQUA (9075 1650);
DISPLAY INVISIBLE (9075 1650);
FORCEPROP 1 LAST HDL_POWER GND
J 1
(9025 1575);
DISPLAY 0.872340 (9025 1575);
PAINT GREEN (9025 1575);
DISPLAY INVISIBLE (9025 1575);
FORCEADD Q_CAP..1
(8600 2025);
FORCEPROP 1 LAST LOCATION C2126
J 0
(8650 2125);
DISPLAY 0.489362 (8650 2125);
PAINT SKYBLUE (8650 2125);
FORCEPROP 2 LAST $SEC 1
J 0
(8650 2225);
DISPLAY 0.680851 (8650 2225);
PAINT MONO (8650 2225);
DISPLAY INVISIBLE (8650 2225);
FORCEPROP 2 LAST CDS_SEC 1
J 0
(8650 2225);
DISPLAY 1.021277 (8650 2225);
DISPLAY INVISIBLE (8650 2225);
FORCEPROP 1 LASTPIN (8600 2125) $PN 1
J 0
(8610 2105);
DISPLAY 0.489362 (8610 2105);
FORCEPROP 1 LASTPIN (8600 1925) $PN 2
J 0
(8610 1905);
DISPLAY 0.489362 (8610 1905);
FORCEPROP 1 LAST MATERIAL X6S
J 0
(8650 1925);
DISPLAY 0.489362 (8650 1925);
PAINT SKYBLUE (8650 1925);
FORCEPROP 1 LAST TOLERANCE 20%
J 0
(8650 1975);
DISPLAY 0.489362 (8650 1975);
PAINT SKYBLUE (8650 1975);
FORCEPROP 1 LAST VALUE 22UF
J 0
(8650 2075);
DISPLAY 0.489362 (8650 2075);
PAINT SKYBLUE (8650 2075);
FORCEPROP 1 LAST PART_NUMBER CH622KMEB02
J 0
(8650 1875);
DISPLAY 0.489362 (8650 1875);
PAINT SKYBLUE (8650 1875);
FORCEPROP 1 LAST VOLTAGE 4V
J 0
(8650 2025);
DISPLAY 0.489362 (8650 2025);
PAINT SKYBLUE (8650 2025);
FORCEPROP 1 LAST PACK_TYPE C0402
J 0
(8650 1825);
DISPLAY 0.489362 (8650 1825);
PAINT SKYBLUE (8650 1825);
FORCEPROP 2 LAST CDS_LIB pure_quanta
J 0
(8600 2025);
PAINT MONO (8600 2025);
DISPLAY INVISIBLE (8600 2025);
FORCEPROP 1 LAST PATH I159
J 0
(8650 2175);
DISPLAY 0.978723 (8650 2175);
PAINT WHITE (8650 2175);
DISPLAY INVISIBLE (8650 2175);
FORCEADD Q_CAP..1
(400 3850);
FORCEPROP 1 LAST LOCATION C2410
J 0
(450 3950);
DISPLAY 0.489362 (450 3950);
PAINT SKYBLUE (450 3950);
FORCEPROP 2 LAST $SEC 1
J 0
(450 4050);
DISPLAY 0.680851 (450 4050);
PAINT MONO (450 4050);
DISPLAY INVISIBLE (450 4050);
FORCEPROP 2 LAST CDS_SEC 1
J 0
(450 4050);
DISPLAY 1.021277 (450 4050);
DISPLAY INVISIBLE (450 4050);
FORCEPROP 1 LASTPIN (400 3950) $PN 1
J 0
(410 3930);
DISPLAY 0.489362 (410 3930);
FORCEPROP 1 LASTPIN (400 3750) $PN 2
J 0
(410 3730);
DISPLAY 0.489362 (410 3730);
FORCEPROP 1 LAST MATERIAL X6S
J 0
(450 3750);
DISPLAY 0.489362 (450 3750);
PAINT SKYBLUE (450 3750);
FORCEPROP 1 LAST TOLERANCE 20%
J 0
(450 3800);
DISPLAY 0.489362 (450 3800);
PAINT SKYBLUE (450 3800);
FORCEPROP 1 LAST VALUE 22UF
J 0
(450 3900);
DISPLAY 0.489362 (450 3900);
PAINT SKYBLUE (450 3900);
FORCEPROP 1 LAST PART_NUMBER CH622KMEB02
J 0
(450 3700);
DISPLAY 0.489362 (450 3700);
PAINT SKYBLUE (450 3700);
FORCEPROP 1 LAST VOLTAGE 4V
J 0
(450 3850);
DISPLAY 0.489362 (450 3850);
PAINT SKYBLUE (450 3850);
FORCEPROP 1 LAST PACK_TYPE C0402
J 0
(450 3650);
DISPLAY 0.489362 (450 3650);
PAINT SKYBLUE (450 3650);
FORCEPROP 2 LAST CDS_LIB pure_quanta
J 0
(400 3850);
PAINT MONO (400 3850);
DISPLAY INVISIBLE (400 3850);
FORCEPROP 1 LAST PATH I16
J 0
(450 4000);
DISPLAY 0.978723 (450 4000);
PAINT WHITE (450 4000);
DISPLAY INVISIBLE (450 4000);
FORCEADD Q_CAP..1
(8600 2650);
FORCEPROP 1 LAST LOCATION C2125
J 0
(8650 2750);
DISPLAY 0.489362 (8650 2750);
PAINT SKYBLUE (8650 2750);
FORCEPROP 2 LAST $SEC 1
J 0
(8650 2850);
DISPLAY 0.680851 (8650 2850);
PAINT MONO (8650 2850);
DISPLAY INVISIBLE (8650 2850);
FORCEPROP 2 LAST CDS_SEC 1
J 0
(8650 2850);
DISPLAY 1.021277 (8650 2850);
DISPLAY INVISIBLE (8650 2850);
FORCEPROP 1 LASTPIN (8600 2750) $PN 1
J 0
(8610 2730);
DISPLAY 0.489362 (8610 2730);
FORCEPROP 1 LASTPIN (8600 2550) $PN 2
J 0
(8610 2530);
DISPLAY 0.489362 (8610 2530);
FORCEPROP 1 LAST MATERIAL X6S
J 0
(8650 2550);
DISPLAY 0.489362 (8650 2550);
PAINT SKYBLUE (8650 2550);
FORCEPROP 1 LAST TOLERANCE 20%
J 0
(8650 2600);
DISPLAY 0.489362 (8650 2600);
PAINT SKYBLUE (8650 2600);
FORCEPROP 1 LAST VALUE 22UF
J 0
(8650 2700);
DISPLAY 0.489362 (8650 2700);
PAINT SKYBLUE (8650 2700);
FORCEPROP 1 LAST PART_NUMBER CH622KMEB02
J 0
(8650 2500);
DISPLAY 0.489362 (8650 2500);
PAINT SKYBLUE (8650 2500);
FORCEPROP 1 LAST VOLTAGE 4V
J 0
(8650 2650);
DISPLAY 0.489362 (8650 2650);
PAINT SKYBLUE (8650 2650);
FORCEPROP 1 LAST PACK_TYPE C0402
J 0
(8650 2450);
DISPLAY 0.489362 (8650 2450);
PAINT SKYBLUE (8650 2450);
FORCEPROP 2 LAST CDS_LIB pure_quanta
J 0
(8600 2650);
PAINT MONO (8600 2650);
DISPLAY INVISIBLE (8600 2650);
FORCEPROP 1 LAST PATH I160
J 0
(8650 2800);
DISPLAY 0.978723 (8650 2800);
PAINT WHITE (8650 2800);
DISPLAY INVISIBLE (8650 2800);
FORCEADD Q_CAP..1
(9000 2025);
FORCEPROP 1 LAST LOCATION C2511
J 0
(9050 2125);
DISPLAY 0.489362 (9050 2125);
PAINT SKYBLUE (9050 2125);
FORCEPROP 2 LAST $SEC 1
J 0
(9050 2225);
DISPLAY 0.680851 (9050 2225);
PAINT MONO (9050 2225);
DISPLAY INVISIBLE (9050 2225);
FORCEPROP 2 LAST CDS_SEC 1
J 0
(9050 2225);
DISPLAY 1.021277 (9050 2225);
DISPLAY INVISIBLE (9050 2225);
FORCEPROP 1 LASTPIN (9000 2125) $PN 1
J 0
(9010 2105);
DISPLAY 0.489362 (9010 2105);
FORCEPROP 1 LASTPIN (9000 1925) $PN 2
J 0
(9010 1905);
DISPLAY 0.489362 (9010 1905);
FORCEPROP 1 LAST MATERIAL X6S
J 0
(9050 1925);
DISPLAY 0.489362 (9050 1925);
PAINT SKYBLUE (9050 1925);
FORCEPROP 1 LAST TOLERANCE 20%
J 0
(9050 1975);
DISPLAY 0.489362 (9050 1975);
PAINT SKYBLUE (9050 1975);
FORCEPROP 1 LAST VALUE 22UF
J 0
(9050 2075);
DISPLAY 0.489362 (9050 2075);
PAINT SKYBLUE (9050 2075);
FORCEPROP 1 LAST PART_NUMBER CH622KMEB02
J 0
(9050 1875);
DISPLAY 0.489362 (9050 1875);
PAINT SKYBLUE (9050 1875);
FORCEPROP 1 LAST VOLTAGE 4V
J 0
(9050 2025);
DISPLAY 0.489362 (9050 2025);
PAINT SKYBLUE (9050 2025);
FORCEPROP 1 LAST PACK_TYPE C0402
J 0
(9050 1825);
DISPLAY 0.489362 (9050 1825);
PAINT SKYBLUE (9050 1825);
FORCEPROP 2 LAST CDS_LIB pure_quanta
J 0
(9000 2025);
PAINT MONO (9000 2025);
DISPLAY INVISIBLE (9000 2025);
FORCEPROP 1 LAST PATH I161
J 0
(9050 2175);
DISPLAY 0.978723 (9050 2175);
PAINT WHITE (9050 2175);
DISPLAY INVISIBLE (9050 2175);
FORCEADD UNIVERSAL_GND..1
(9000 2300);
FORCEPROP 3 LASTPIN (9000 2350) SIG_NAME GND\g
J 0
(9010 2360);
DISPLAY 0.659574 (9010 2360);
PAINT MONO (9010 2360);
DISPLAY INVISIBLE (9010 2360);
FORCEPROP 2 LAST CDS_LIB pure_quanta_power
J 0
(9000 2300);
PAINT MONO (9000 2300);
DISPLAY INVISIBLE (9000 2300);
FORCEPROP 1 LAST PATH I162
J 0
(9075 2300);
DISPLAY 0.872340 (9075 2300);
PAINT AQUA (9075 2300);
DISPLAY INVISIBLE (9075 2300);
FORCEPROP 1 LAST HDL_POWER GND
J 1
(9025 2225);
DISPLAY 0.872340 (9025 2225);
PAINT GREEN (9025 2225);
DISPLAY INVISIBLE (9025 2225);
FORCEADD Q_CAP..1
(9000 2650);
FORCEPROP 1 LAST LOCATION C2510
J 0
(9050 2750);
DISPLAY 0.489362 (9050 2750);
PAINT SKYBLUE (9050 2750);
FORCEPROP 2 LAST $SEC 1
J 0
(9050 2850);
DISPLAY 0.680851 (9050 2850);
PAINT MONO (9050 2850);
DISPLAY INVISIBLE (9050 2850);
FORCEPROP 2 LAST CDS_SEC 1
J 0
(9050 2850);
DISPLAY 1.021277 (9050 2850);
DISPLAY INVISIBLE (9050 2850);
FORCEPROP 1 LASTPIN (9000 2750) $PN 1
J 0
(9010 2730);
DISPLAY 0.489362 (9010 2730);
FORCEPROP 1 LASTPIN (9000 2550) $PN 2
J 0
(9010 2530);
DISPLAY 0.489362 (9010 2530);
FORCEPROP 1 LAST MATERIAL X6S
J 0
(9050 2550);
DISPLAY 0.489362 (9050 2550);
PAINT SKYBLUE (9050 2550);
FORCEPROP 1 LAST TOLERANCE 20%
J 0
(9050 2600);
DISPLAY 0.489362 (9050 2600);
PAINT SKYBLUE (9050 2600);
FORCEPROP 1 LAST VALUE 22UF
J 0
(9050 2700);
DISPLAY 0.489362 (9050 2700);
PAINT SKYBLUE (9050 2700);
FORCEPROP 1 LAST PART_NUMBER CH622KMEB02
J 0
(9050 2500);
DISPLAY 0.489362 (9050 2500);
PAINT SKYBLUE (9050 2500);
FORCEPROP 1 LAST VOLTAGE 4V
J 0
(9050 2650);
DISPLAY 0.489362 (9050 2650);
PAINT SKYBLUE (9050 2650);
FORCEPROP 1 LAST PACK_TYPE C0402
J 0
(9050 2450);
DISPLAY 0.489362 (9050 2450);
PAINT SKYBLUE (9050 2450);
FORCEPROP 2 LAST CDS_LIB pure_quanta
J 0
(9000 2650);
PAINT MONO (9000 2650);
DISPLAY INVISIBLE (9000 2650);
FORCEPROP 1 LAST PATH I163
J 0
(9050 2800);
DISPLAY 0.978723 (9050 2800);
PAINT WHITE (9050 2800);
DISPLAY INVISIBLE (9050 2800);
FORCEADD Q_CAP..1
(8600 3325);
FORCEPROP 1 LAST LOCATION C2124
J 0
(8650 3425);
DISPLAY 0.489362 (8650 3425);
PAINT SKYBLUE (8650 3425);
FORCEPROP 2 LAST $SEC 1
J 0
(8650 3525);
DISPLAY 0.680851 (8650 3525);
PAINT MONO (8650 3525);
DISPLAY INVISIBLE (8650 3525);
FORCEPROP 2 LAST CDS_SEC 1
J 0
(8650 3525);
DISPLAY 1.021277 (8650 3525);
DISPLAY INVISIBLE (8650 3525);
FORCEPROP 1 LASTPIN (8600 3425) $PN 1
J 0
(8610 3405);
DISPLAY 0.489362 (8610 3405);
FORCEPROP 1 LASTPIN (8600 3225) $PN 2
J 0
(8610 3205);
DISPLAY 0.489362 (8610 3205);
FORCEPROP 1 LAST MATERIAL X6S
J 0
(8650 3225);
DISPLAY 0.489362 (8650 3225);
PAINT SKYBLUE (8650 3225);
FORCEPROP 1 LAST TOLERANCE 20%
J 0
(8650 3275);
DISPLAY 0.489362 (8650 3275);
PAINT SKYBLUE (8650 3275);
FORCEPROP 1 LAST VALUE 22UF
J 0
(8650 3375);
DISPLAY 0.489362 (8650 3375);
PAINT SKYBLUE (8650 3375);
FORCEPROP 1 LAST PART_NUMBER CH622KMEB02
J 0
(8650 3175);
DISPLAY 0.489362 (8650 3175);
PAINT SKYBLUE (8650 3175);
FORCEPROP 1 LAST VOLTAGE 4V
J 0
(8650 3325);
DISPLAY 0.489362 (8650 3325);
PAINT SKYBLUE (8650 3325);
FORCEPROP 1 LAST PACK_TYPE C0402
J 0
(8650 3125);
DISPLAY 0.489362 (8650 3125);
PAINT SKYBLUE (8650 3125);
FORCEPROP 2 LAST CDS_LIB pure_quanta
J 0
(8600 3325);
PAINT MONO (8600 3325);
DISPLAY INVISIBLE (8600 3325);
FORCEPROP 1 LAST PATH I164
J 0
(8650 3475);
DISPLAY 0.978723 (8650 3475);
PAINT WHITE (8650 3475);
DISPLAY INVISIBLE (8650 3475);
FORCEADD UNIVERSAL_GND..1
(9000 2950);
FORCEPROP 3 LASTPIN (9000 3000) SIG_NAME GND\g
J 0
(9010 3010);
DISPLAY 0.659574 (9010 3010);
PAINT MONO (9010 3010);
DISPLAY INVISIBLE (9010 3010);
FORCEPROP 2 LAST CDS_LIB pure_quanta_power
J 0
(9000 2950);
PAINT MONO (9000 2950);
DISPLAY INVISIBLE (9000 2950);
FORCEPROP 1 LAST PATH I165
J 0
(9075 2950);
DISPLAY 0.872340 (9075 2950);
PAINT AQUA (9075 2950);
DISPLAY INVISIBLE (9075 2950);
FORCEPROP 1 LAST HDL_POWER GND
J 1
(9025 2875);
DISPLAY 0.872340 (9025 2875);
PAINT GREEN (9025 2875);
DISPLAY INVISIBLE (9025 2875);
FORCEADD Q_CAP..1
(9000 3325);
FORCEPROP 1 LAST LOCATION C2128
J 0
(9050 3425);
DISPLAY 0.489362 (9050 3425);
PAINT SKYBLUE (9050 3425);
FORCEPROP 2 LAST $SEC 1
J 0
(9050 3525);
DISPLAY 0.680851 (9050 3525);
PAINT MONO (9050 3525);
DISPLAY INVISIBLE (9050 3525);
FORCEPROP 2 LAST CDS_SEC 1
J 0
(9050 3525);
DISPLAY 1.021277 (9050 3525);
DISPLAY INVISIBLE (9050 3525);
FORCEPROP 1 LASTPIN (9000 3425) $PN 1
J 0
(9010 3405);
DISPLAY 0.489362 (9010 3405);
FORCEPROP 1 LASTPIN (9000 3225) $PN 2
J 0
(9010 3205);
DISPLAY 0.489362 (9010 3205);
FORCEPROP 1 LAST MATERIAL X6S
J 0
(9050 3225);
DISPLAY 0.489362 (9050 3225);
PAINT SKYBLUE (9050 3225);
FORCEPROP 1 LAST TOLERANCE 20%
J 0
(9050 3275);
DISPLAY 0.489362 (9050 3275);
PAINT SKYBLUE (9050 3275);
FORCEPROP 1 LAST VALUE 22UF
J 0
(9050 3375);
DISPLAY 0.489362 (9050 3375);
PAINT SKYBLUE (9050 3375);
FORCEPROP 1 LAST PART_NUMBER CH622KMEB02
J 0
(9050 3175);
DISPLAY 0.489362 (9050 3175);
PAINT SKYBLUE (9050 3175);
FORCEPROP 1 LAST VOLTAGE 4V
J 0
(9050 3325);
DISPLAY 0.489362 (9050 3325);
PAINT SKYBLUE (9050 3325);
FORCEPROP 1 LAST PACK_TYPE C0402
J 0
(9050 3125);
DISPLAY 0.489362 (9050 3125);
PAINT SKYBLUE (9050 3125);
FORCEPROP 2 LAST CDS_LIB pure_quanta
J 0
(9000 3325);
PAINT MONO (9000 3325);
DISPLAY INVISIBLE (9000 3325);
FORCEPROP 1 LAST PATH I166
J 0
(9050 3475);
DISPLAY 0.978723 (9050 3475);
PAINT WHITE (9050 3475);
DISPLAY INVISIBLE (9050 3475);
FORCEADD UNIVERSAL_GND..1
(8975 4700);
FORCEPROP 3 LASTPIN (8975 4750) SIG_NAME GND\g
J 0
(8985 4760);
DISPLAY 0.659574 (8985 4760);
PAINT MONO (8985 4760);
DISPLAY INVISIBLE (8985 4760);
FORCEPROP 2 LAST CDS_LIB pure_quanta_power
J 0
(8975 4700);
PAINT MONO (8975 4700);
DISPLAY INVISIBLE (8975 4700);
FORCEPROP 1 LAST PATH I167
J 0
(9050 4700);
DISPLAY 0.872340 (9050 4700);
PAINT AQUA (9050 4700);
DISPLAY INVISIBLE (9050 4700);
FORCEPROP 1 LAST HDL_POWER GND
J 1
(9000 4625);
DISPLAY 0.872340 (9000 4625);
PAINT GREEN (9000 4625);
DISPLAY INVISIBLE (9000 4625);
FORCEADD Q_CAP..1
(8575 5075);
FORCEPROP 1 LAST LOCATION C2123
J 0
(8625 5175);
DISPLAY 0.489362 (8625 5175);
PAINT SKYBLUE (8625 5175);
FORCEPROP 2 LAST $SEC 1
J 0
(8625 5275);
DISPLAY 0.680851 (8625 5275);
PAINT MONO (8625 5275);
DISPLAY INVISIBLE (8625 5275);
FORCEPROP 2 LAST CDS_SEC 1
J 0
(8625 5275);
DISPLAY 1.021277 (8625 5275);
DISPLAY INVISIBLE (8625 5275);
FORCEPROP 1 LASTPIN (8575 5175) $PN 1
J 0
(8585 5155);
DISPLAY 0.489362 (8585 5155);
FORCEPROP 1 LASTPIN (8575 4975) $PN 2
J 0
(8585 4955);
DISPLAY 0.489362 (8585 4955);
FORCEPROP 1 LAST MATERIAL X6S
J 0
(8625 4975);
DISPLAY 0.489362 (8625 4975);
PAINT SKYBLUE (8625 4975);
FORCEPROP 1 LAST TOLERANCE 20%
J 0
(8625 5025);
DISPLAY 0.489362 (8625 5025);
PAINT SKYBLUE (8625 5025);
FORCEPROP 1 LAST VALUE 22UF
J 0
(8625 5125);
DISPLAY 0.489362 (8625 5125);
PAINT SKYBLUE (8625 5125);
FORCEPROP 1 LAST PART_NUMBER CH622KMEB02
J 0
(8625 4925);
DISPLAY 0.489362 (8625 4925);
PAINT SKYBLUE (8625 4925);
FORCEPROP 1 LAST VOLTAGE 4V
J 0
(8625 5075);
DISPLAY 0.489362 (8625 5075);
PAINT SKYBLUE (8625 5075);
FORCEPROP 1 LAST PACK_TYPE C0402
J 0
(8625 4875);
DISPLAY 0.489362 (8625 4875);
PAINT SKYBLUE (8625 4875);
FORCEPROP 2 LAST CDS_LIB pure_quanta
J 0
(8575 5075);
PAINT MONO (8575 5075);
DISPLAY INVISIBLE (8575 5075);
FORCEPROP 1 LAST PATH I168
J 0
(8625 5225);
DISPLAY 0.978723 (8625 5225);
PAINT WHITE (8625 5225);
DISPLAY INVISIBLE (8625 5225);
FORCEADD Q_CAP..1
(8575 5875);
FORCEPROP 1 LAST LOCATION C2122
J 0
(8625 5975);
DISPLAY 0.489362 (8625 5975);
PAINT SKYBLUE (8625 5975);
FORCEPROP 2 LAST $SEC 1
J 0
(8625 6075);
DISPLAY 0.680851 (8625 6075);
PAINT MONO (8625 6075);
DISPLAY INVISIBLE (8625 6075);
FORCEPROP 2 LAST CDS_SEC 1
J 0
(8625 6075);
DISPLAY 1.021277 (8625 6075);
DISPLAY INVISIBLE (8625 6075);
FORCEPROP 1 LASTPIN (8575 5975) $PN 1
J 0
(8585 5955);
DISPLAY 0.489362 (8585 5955);
FORCEPROP 1 LASTPIN (8575 5775) $PN 2
J 0
(8585 5755);
DISPLAY 0.489362 (8585 5755);
FORCEPROP 1 LAST MATERIAL X6S
J 0
(8625 5775);
DISPLAY 0.489362 (8625 5775);
PAINT SKYBLUE (8625 5775);
FORCEPROP 1 LAST TOLERANCE 20%
J 0
(8625 5825);
DISPLAY 0.489362 (8625 5825);
PAINT SKYBLUE (8625 5825);
FORCEPROP 1 LAST VALUE 22UF
J 0
(8625 5925);
DISPLAY 0.489362 (8625 5925);
PAINT SKYBLUE (8625 5925);
FORCEPROP 1 LAST PART_NUMBER CH622KMEB02
J 0
(8625 5725);
DISPLAY 0.489362 (8625 5725);
PAINT SKYBLUE (8625 5725);
FORCEPROP 1 LAST VOLTAGE 4V
J 0
(8625 5875);
DISPLAY 0.489362 (8625 5875);
PAINT SKYBLUE (8625 5875);
FORCEPROP 1 LAST PACK_TYPE C0402
J 0
(8625 5675);
DISPLAY 0.489362 (8625 5675);
PAINT SKYBLUE (8625 5675);
FORCEPROP 2 LAST CDS_LIB pure_quanta
J 0
(8575 5875);
PAINT MONO (8575 5875);
DISPLAY INVISIBLE (8575 5875);
FORCEPROP 1 LAST PATH I169
J 0
(8625 6025);
DISPLAY 0.978723 (8625 6025);
PAINT WHITE (8625 6025);
DISPLAY INVISIBLE (8625 6025);
FORCEADD Q_CAP..1
(850 3150);
FORCEPROP 1 LAST LOCATION C2418
J 0
(900 3250);
DISPLAY 0.489362 (900 3250);
PAINT SKYBLUE (900 3250);
FORCEPROP 2 LAST $SEC 1
J 0
(900 3350);
DISPLAY 0.680851 (900 3350);
PAINT MONO (900 3350);
DISPLAY INVISIBLE (900 3350);
FORCEPROP 2 LAST CDS_SEC 1
J 0
(900 3350);
DISPLAY 1.021277 (900 3350);
DISPLAY INVISIBLE (900 3350);
FORCEPROP 1 LASTPIN (850 3250) $PN 1
J 0
(860 3230);
DISPLAY 0.489362 (860 3230);
FORCEPROP 1 LASTPIN (850 3050) $PN 2
J 0
(860 3030);
DISPLAY 0.489362 (860 3030);
FORCEPROP 1 LAST MATERIAL X6S
J 0
(900 3050);
DISPLAY 0.489362 (900 3050);
PAINT SKYBLUE (900 3050);
FORCEPROP 1 LAST TOLERANCE 20%
J 0
(900 3100);
DISPLAY 0.489362 (900 3100);
PAINT SKYBLUE (900 3100);
FORCEPROP 1 LAST VALUE 22UF
J 0
(900 3200);
DISPLAY 0.489362 (900 3200);
PAINT SKYBLUE (900 3200);
FORCEPROP 1 LAST PART_NUMBER CH622KMEB02
J 0
(900 3000);
DISPLAY 0.489362 (900 3000);
PAINT SKYBLUE (900 3000);
FORCEPROP 1 LAST VOLTAGE 4V
J 0
(900 3150);
DISPLAY 0.489362 (900 3150);
PAINT SKYBLUE (900 3150);
FORCEPROP 1 LAST PACK_TYPE C0402
J 0
(900 2950);
DISPLAY 0.489362 (900 2950);
PAINT SKYBLUE (900 2950);
FORCEPROP 2 LAST CDS_LIB pure_quanta
J 0
(850 3150);
PAINT MONO (850 3150);
DISPLAY INVISIBLE (850 3150);
FORCEPROP 1 LAST PATH I17
J 0
(900 3300);
DISPLAY 0.978723 (900 3300);
PAINT WHITE (900 3300);
DISPLAY INVISIBLE (900 3300);
FORCEADD Q_CAP..1
(8975 5075);
FORCEPROP 1 LAST LOCATION C2509
J 0
(9025 5175);
DISPLAY 0.489362 (9025 5175);
PAINT SKYBLUE (9025 5175);
FORCEPROP 2 LAST $SEC 1
J 0
(9025 5275);
DISPLAY 0.680851 (9025 5275);
PAINT MONO (9025 5275);
DISPLAY INVISIBLE (9025 5275);
FORCEPROP 2 LAST CDS_SEC 1
J 0
(9025 5275);
DISPLAY 1.021277 (9025 5275);
DISPLAY INVISIBLE (9025 5275);
FORCEPROP 1 LASTPIN (8975 5175) $PN 1
J 0
(8985 5155);
DISPLAY 0.489362 (8985 5155);
FORCEPROP 1 LASTPIN (8975 4975) $PN 2
J 0
(8985 4955);
DISPLAY 0.489362 (8985 4955);
FORCEPROP 1 LAST MATERIAL X6S
J 0
(9025 4975);
DISPLAY 0.489362 (9025 4975);
PAINT SKYBLUE (9025 4975);
FORCEPROP 1 LAST TOLERANCE 20%
J 0
(9025 5025);
DISPLAY 0.489362 (9025 5025);
PAINT SKYBLUE (9025 5025);
FORCEPROP 1 LAST VALUE 22UF
J 0
(9025 5125);
DISPLAY 0.489362 (9025 5125);
PAINT SKYBLUE (9025 5125);
FORCEPROP 1 LAST PART_NUMBER CH622KMEB02
J 0
(9025 4925);
DISPLAY 0.489362 (9025 4925);
PAINT SKYBLUE (9025 4925);
FORCEPROP 1 LAST VOLTAGE 4V
J 0
(9025 5075);
DISPLAY 0.489362 (9025 5075);
PAINT SKYBLUE (9025 5075);
FORCEPROP 1 LAST PACK_TYPE C0402
J 0
(9025 4875);
DISPLAY 0.489362 (9025 4875);
PAINT SKYBLUE (9025 4875);
FORCEPROP 2 LAST CDS_LIB pure_quanta
J 0
(8975 5075);
PAINT MONO (8975 5075);
DISPLAY INVISIBLE (8975 5075);
FORCEPROP 1 LAST PATH I170
J 0
(9025 5225);
DISPLAY 0.978723 (9025 5225);
PAINT WHITE (9025 5225);
DISPLAY INVISIBLE (9025 5225);
FORCEADD UNIVERSAL_GND..1
(8975 5500);
FORCEPROP 3 LASTPIN (8975 5550) SIG_NAME GND\g
J 0
(8985 5560);
DISPLAY 0.659574 (8985 5560);
PAINT MONO (8985 5560);
DISPLAY INVISIBLE (8985 5560);
FORCEPROP 2 LAST CDS_LIB pure_quanta_power
J 0
(8975 5500);
PAINT MONO (8975 5500);
DISPLAY INVISIBLE (8975 5500);
FORCEPROP 1 LAST PATH I171
J 0
(9050 5500);
DISPLAY 0.872340 (9050 5500);
PAINT AQUA (9050 5500);
DISPLAY INVISIBLE (9050 5500);
FORCEPROP 1 LAST HDL_POWER GND
J 1
(9000 5425);
DISPLAY 0.872340 (9000 5425);
PAINT GREEN (9000 5425);
DISPLAY INVISIBLE (9000 5425);
FORCEADD Q_CAP..1
(8975 5875);
FORCEPROP 1 LAST LOCATION C2127
J 0
(9025 5975);
DISPLAY 0.489362 (9025 5975);
PAINT SKYBLUE (9025 5975);
FORCEPROP 2 LAST $SEC 1
J 0
(9025 6075);
DISPLAY 0.680851 (9025 6075);
PAINT MONO (9025 6075);
DISPLAY INVISIBLE (9025 6075);
FORCEPROP 2 LAST CDS_SEC 1
J 0
(9025 6075);
DISPLAY 1.021277 (9025 6075);
DISPLAY INVISIBLE (9025 6075);
FORCEPROP 1 LASTPIN (8975 5975) $PN 1
J 0
(8985 5955);
DISPLAY 0.489362 (8985 5955);
FORCEPROP 1 LASTPIN (8975 5775) $PN 2
J 0
(8985 5755);
DISPLAY 0.489362 (8985 5755);
FORCEPROP 1 LAST MATERIAL X6S
J 0
(9025 5775);
DISPLAY 0.489362 (9025 5775);
PAINT SKYBLUE (9025 5775);
FORCEPROP 1 LAST TOLERANCE 20%
J 0
(9025 5825);
DISPLAY 0.489362 (9025 5825);
PAINT SKYBLUE (9025 5825);
FORCEPROP 1 LAST VALUE 22UF
J 0
(9025 5925);
DISPLAY 0.489362 (9025 5925);
PAINT SKYBLUE (9025 5925);
FORCEPROP 1 LAST PART_NUMBER CH622KMEB02
J 0
(9025 5725);
DISPLAY 0.489362 (9025 5725);
PAINT SKYBLUE (9025 5725);
FORCEPROP 1 LAST VOLTAGE 4V
J 0
(9025 5875);
DISPLAY 0.489362 (9025 5875);
PAINT SKYBLUE (9025 5875);
FORCEPROP 1 LAST PACK_TYPE C0402
J 0
(9025 5675);
DISPLAY 0.489362 (9025 5675);
PAINT SKYBLUE (9025 5675);
FORCEPROP 2 LAST CDS_LIB pure_quanta
J 0
(8975 5875);
PAINT MONO (8975 5875);
DISPLAY INVISIBLE (8975 5875);
FORCEPROP 1 LAST PATH I172
J 0
(9025 6025);
DISPLAY 0.978723 (9025 6025);
PAINT WHITE (9025 6025);
DISPLAY INVISIBLE (9025 6025);
FORCEADD Q_CAP..1
(2650 5875);
FORCEPROP 1 LAST LOCATION C2442
J 0
(2700 5975);
DISPLAY 0.489362 (2700 5975);
PAINT SKYBLUE (2700 5975);
FORCEPROP 2 LAST $SEC 1
J 0
(2700 6075);
DISPLAY 0.680851 (2700 6075);
PAINT MONO (2700 6075);
DISPLAY INVISIBLE (2700 6075);
FORCEPROP 2 LAST CDS_SEC 1
J 0
(2700 6075);
DISPLAY 1.021277 (2700 6075);
DISPLAY INVISIBLE (2700 6075);
FORCEPROP 1 LASTPIN (2650 5975) $PN 1
J 0
(2660 5955);
DISPLAY 0.489362 (2660 5955);
FORCEPROP 1 LASTPIN (2650 5775) $PN 2
J 0
(2660 5755);
DISPLAY 0.489362 (2660 5755);
FORCEPROP 1 LAST MATERIAL X6S
J 0
(2700 5775);
DISPLAY 0.489362 (2700 5775);
PAINT SKYBLUE (2700 5775);
FORCEPROP 1 LAST TOLERANCE 20%
J 0
(2700 5825);
DISPLAY 0.489362 (2700 5825);
PAINT SKYBLUE (2700 5825);
FORCEPROP 1 LAST VALUE 22UF
J 0
(2700 5925);
DISPLAY 0.489362 (2700 5925);
PAINT SKYBLUE (2700 5925);
FORCEPROP 1 LAST PART_NUMBER CH622KMEB02
J 0
(2700 5725);
DISPLAY 0.489362 (2700 5725);
PAINT SKYBLUE (2700 5725);
FORCEPROP 1 LAST VOLTAGE 4V
J 0
(2700 5875);
DISPLAY 0.489362 (2700 5875);
PAINT SKYBLUE (2700 5875);
FORCEPROP 1 LAST PACK_TYPE C0402
J 0
(2700 5675);
DISPLAY 0.489362 (2700 5675);
PAINT SKYBLUE (2700 5675);
FORCEPROP 2 LAST CDS_LIB pure_quanta
J 0
(2650 5875);
PAINT MONO (2650 5875);
DISPLAY INVISIBLE (2650 5875);
FORCEPROP 1 LAST PATH I173
J 0
(2700 6025);
DISPLAY 0.978723 (2700 6025);
PAINT WHITE (2700 6025);
DISPLAY INVISIBLE (2700 6025);
FORCEADD Q_CAP..1
(2200 5875);
FORCEPROP 1 LAST LOCATION C2435
J 0
(2250 5975);
DISPLAY 0.489362 (2250 5975);
PAINT SKYBLUE (2250 5975);
FORCEPROP 2 LAST $SEC 1
J 0
(2250 6075);
DISPLAY 0.680851 (2250 6075);
PAINT MONO (2250 6075);
DISPLAY INVISIBLE (2250 6075);
FORCEPROP 2 LAST CDS_SEC 1
J 0
(2250 6075);
DISPLAY 1.021277 (2250 6075);
DISPLAY INVISIBLE (2250 6075);
FORCEPROP 1 LASTPIN (2200 5975) $PN 1
J 0
(2210 5955);
DISPLAY 0.489362 (2210 5955);
FORCEPROP 1 LASTPIN (2200 5775) $PN 2
J 0
(2210 5755);
DISPLAY 0.489362 (2210 5755);
FORCEPROP 1 LAST MATERIAL X6S
J 0
(2250 5775);
DISPLAY 0.489362 (2250 5775);
PAINT SKYBLUE (2250 5775);
FORCEPROP 1 LAST TOLERANCE 20%
J 0
(2250 5825);
DISPLAY 0.489362 (2250 5825);
PAINT SKYBLUE (2250 5825);
FORCEPROP 1 LAST VALUE 22UF
J 0
(2250 5925);
DISPLAY 0.489362 (2250 5925);
PAINT SKYBLUE (2250 5925);
FORCEPROP 1 LAST PART_NUMBER CH622KMEB02
J 0
(2250 5725);
DISPLAY 0.489362 (2250 5725);
PAINT SKYBLUE (2250 5725);
FORCEPROP 1 LAST VOLTAGE 4V
J 0
(2250 5875);
DISPLAY 0.489362 (2250 5875);
PAINT SKYBLUE (2250 5875);
FORCEPROP 1 LAST PACK_TYPE C0402
J 0
(2250 5675);
DISPLAY 0.489362 (2250 5675);
PAINT SKYBLUE (2250 5675);
FORCEPROP 2 LAST CDS_LIB pure_quanta
J 0
(2200 5875);
PAINT MONO (2200 5875);
DISPLAY INVISIBLE (2200 5875);
FORCEPROP 1 LAST PATH I174
J 0
(2250 6025);
DISPLAY 0.978723 (2250 6025);
PAINT WHITE (2250 6025);
DISPLAY INVISIBLE (2250 6025);
FORCEADD Q_CAP..1
(1750 5875);
FORCEPROP 1 LAST LOCATION C2428
J 0
(1800 5975);
DISPLAY 0.489362 (1800 5975);
PAINT SKYBLUE (1800 5975);
FORCEPROP 2 LAST $SEC 1
J 0
(1800 6075);
DISPLAY 0.680851 (1800 6075);
PAINT MONO (1800 6075);
DISPLAY INVISIBLE (1800 6075);
FORCEPROP 2 LAST CDS_SEC 1
J 0
(1800 6075);
DISPLAY 1.021277 (1800 6075);
DISPLAY INVISIBLE (1800 6075);
FORCEPROP 1 LASTPIN (1750 5975) $PN 1
J 0
(1760 5955);
DISPLAY 0.489362 (1760 5955);
FORCEPROP 1 LASTPIN (1750 5775) $PN 2
J 0
(1760 5755);
DISPLAY 0.489362 (1760 5755);
FORCEPROP 1 LAST MATERIAL X6S
J 0
(1800 5775);
DISPLAY 0.489362 (1800 5775);
PAINT SKYBLUE (1800 5775);
FORCEPROP 1 LAST TOLERANCE 20%
J 0
(1800 5825);
DISPLAY 0.489362 (1800 5825);
PAINT SKYBLUE (1800 5825);
FORCEPROP 1 LAST VALUE 22UF
J 0
(1800 5925);
DISPLAY 0.489362 (1800 5925);
PAINT SKYBLUE (1800 5925);
FORCEPROP 1 LAST PART_NUMBER CH622KMEB02
J 0
(1800 5725);
DISPLAY 0.489362 (1800 5725);
PAINT SKYBLUE (1800 5725);
FORCEPROP 1 LAST VOLTAGE 4V
J 0
(1800 5875);
DISPLAY 0.489362 (1800 5875);
PAINT SKYBLUE (1800 5875);
FORCEPROP 1 LAST PACK_TYPE C0402
J 0
(1800 5675);
DISPLAY 0.489362 (1800 5675);
PAINT SKYBLUE (1800 5675);
FORCEPROP 2 LAST CDS_LIB pure_quanta
J 0
(1750 5875);
PAINT MONO (1750 5875);
DISPLAY INVISIBLE (1750 5875);
FORCEPROP 1 LAST PATH I175
J 0
(1800 6025);
DISPLAY 0.978723 (1800 6025);
PAINT WHITE (1800 6025);
DISPLAY INVISIBLE (1800 6025);
FORCEADD Q_CAP..1
(850 3850);
FORCEPROP 1 LAST LOCATION C2417
J 0
(900 3950);
DISPLAY 0.489362 (900 3950);
PAINT SKYBLUE (900 3950);
FORCEPROP 2 LAST $SEC 1
J 0
(900 4050);
DISPLAY 0.680851 (900 4050);
PAINT MONO (900 4050);
DISPLAY INVISIBLE (900 4050);
FORCEPROP 2 LAST CDS_SEC 1
J 0
(900 4050);
DISPLAY 1.021277 (900 4050);
DISPLAY INVISIBLE (900 4050);
FORCEPROP 1 LASTPIN (850 3950) $PN 1
J 0
(860 3930);
DISPLAY 0.489362 (860 3930);
FORCEPROP 1 LASTPIN (850 3750) $PN 2
J 0
(860 3730);
DISPLAY 0.489362 (860 3730);
FORCEPROP 1 LAST MATERIAL X6S
J 0
(900 3750);
DISPLAY 0.489362 (900 3750);
PAINT SKYBLUE (900 3750);
FORCEPROP 1 LAST TOLERANCE 20%
J 0
(900 3800);
DISPLAY 0.489362 (900 3800);
PAINT SKYBLUE (900 3800);
FORCEPROP 1 LAST VALUE 22UF
J 0
(900 3900);
DISPLAY 0.489362 (900 3900);
PAINT SKYBLUE (900 3900);
FORCEPROP 1 LAST PART_NUMBER CH622KMEB02
J 0
(900 3700);
DISPLAY 0.489362 (900 3700);
PAINT SKYBLUE (900 3700);
FORCEPROP 1 LAST VOLTAGE 4V
J 0
(900 3850);
DISPLAY 0.489362 (900 3850);
PAINT SKYBLUE (900 3850);
FORCEPROP 1 LAST PACK_TYPE C0402
J 0
(900 3650);
DISPLAY 0.489362 (900 3650);
PAINT SKYBLUE (900 3650);
FORCEPROP 2 LAST CDS_LIB pure_quanta
J 0
(850 3850);
PAINT MONO (850 3850);
DISPLAY INVISIBLE (850 3850);
FORCEPROP 1 LAST PATH I18
J 0
(900 4000);
DISPLAY 0.978723 (900 4000);
PAINT WHITE (900 4000);
DISPLAY INVISIBLE (900 4000);
FORCEADD Q_CAP..1
(1300 2475);
FORCEPROP 1 LAST LOCATION C2426
J 0
(1350 2575);
DISPLAY 0.489362 (1350 2575);
PAINT SKYBLUE (1350 2575);
FORCEPROP 2 LAST $SEC 1
J 0
(1350 2675);
DISPLAY 0.680851 (1350 2675);
PAINT MONO (1350 2675);
DISPLAY INVISIBLE (1350 2675);
FORCEPROP 2 LAST CDS_SEC 1
J 0
(1350 2675);
DISPLAY 1.021277 (1350 2675);
DISPLAY INVISIBLE (1350 2675);
FORCEPROP 1 LASTPIN (1300 2575) $PN 1
J 0
(1310 2555);
DISPLAY 0.489362 (1310 2555);
FORCEPROP 1 LASTPIN (1300 2375) $PN 2
J 0
(1310 2355);
DISPLAY 0.489362 (1310 2355);
FORCEPROP 1 LAST MATERIAL X6S
J 0
(1350 2375);
DISPLAY 0.489362 (1350 2375);
PAINT SKYBLUE (1350 2375);
FORCEPROP 1 LAST TOLERANCE 20%
J 0
(1350 2425);
DISPLAY 0.489362 (1350 2425);
PAINT SKYBLUE (1350 2425);
FORCEPROP 1 LAST VALUE 22UF
J 0
(1350 2525);
DISPLAY 0.489362 (1350 2525);
PAINT SKYBLUE (1350 2525);
FORCEPROP 1 LAST PART_NUMBER CH622KMEB02
J 0
(1350 2325);
DISPLAY 0.489362 (1350 2325);
PAINT SKYBLUE (1350 2325);
FORCEPROP 1 LAST VOLTAGE 4V
J 0
(1350 2475);
DISPLAY 0.489362 (1350 2475);
PAINT SKYBLUE (1350 2475);
FORCEPROP 1 LAST PACK_TYPE C0402
J 0
(1350 2275);
DISPLAY 0.489362 (1350 2275);
PAINT SKYBLUE (1350 2275);
FORCEPROP 2 LAST CDS_LIB pure_quanta
J 0
(1300 2475);
PAINT MONO (1300 2475);
DISPLAY INVISIBLE (1300 2475);
FORCEPROP 1 LAST PATH I19
J 0
(1350 2625);
DISPLAY 0.978723 (1350 2625);
PAINT WHITE (1350 2625);
DISPLAY INVISIBLE (1350 2625);
FORCEADD UNIVERSAL_POWER..1
(400 1350);
FORCEPROP 3 LASTPIN (400 1300) SIG_NAME PVDDCR_SOC_P1\g
J 0
(410 1310);
DISPLAY 0.659574 (410 1310);
PAINT MONO (410 1310);
DISPLAY INVISIBLE (410 1310);
FORCEPROP 1 LAST HDL_POWER PVDDCR_SOC_P1
J 1
(400 1400);
DISPLAY 0.489362 (400 1400);
PAINT GREEN (400 1400);
FORCEPROP 2 LAST CDS_LIB pure_quanta_power
J 0
(400 1350);
DISPLAY INVISIBLE (400 1350);
FORCEPROP 1 LAST PATH I2
J 0
(450 1375);
DISPLAY 0.872340 (450 1375);
PAINT AQUA (450 1375);
DISPLAY INVISIBLE (450 1375);
FORCEADD Q_CAP..1
(1750 2475);
FORCEPROP 1 LAST LOCATION C2433
J 0
(1800 2575);
DISPLAY 0.489362 (1800 2575);
PAINT SKYBLUE (1800 2575);
FORCEPROP 2 LAST $SEC 1
J 0
(1800 2675);
DISPLAY 0.680851 (1800 2675);
PAINT MONO (1800 2675);
DISPLAY INVISIBLE (1800 2675);
FORCEPROP 2 LAST CDS_SEC 1
J 0
(1800 2675);
DISPLAY 1.021277 (1800 2675);
DISPLAY INVISIBLE (1800 2675);
FORCEPROP 1 LASTPIN (1750 2575) $PN 1
J 0
(1760 2555);
DISPLAY 0.489362 (1760 2555);
FORCEPROP 1 LASTPIN (1750 2375) $PN 2
J 0
(1760 2355);
DISPLAY 0.489362 (1760 2355);
FORCEPROP 1 LAST MATERIAL X6S
J 0
(1800 2375);
DISPLAY 0.489362 (1800 2375);
PAINT SKYBLUE (1800 2375);
FORCEPROP 1 LAST TOLERANCE 20%
J 0
(1800 2425);
DISPLAY 0.489362 (1800 2425);
PAINT SKYBLUE (1800 2425);
FORCEPROP 1 LAST VALUE 22UF
J 0
(1800 2525);
DISPLAY 0.489362 (1800 2525);
PAINT SKYBLUE (1800 2525);
FORCEPROP 1 LAST PART_NUMBER CH622KMEB02
J 0
(1800 2325);
DISPLAY 0.489362 (1800 2325);
PAINT SKYBLUE (1800 2325);
FORCEPROP 1 LAST VOLTAGE 4V
J 0
(1800 2475);
DISPLAY 0.489362 (1800 2475);
PAINT SKYBLUE (1800 2475);
FORCEPROP 1 LAST PACK_TYPE C0402
J 0
(1800 2275);
DISPLAY 0.489362 (1800 2275);
PAINT SKYBLUE (1800 2275);
FORCEPROP 2 LAST CDS_LIB pure_quanta
J 0
(1750 2475);
PAINT MONO (1750 2475);
DISPLAY INVISIBLE (1750 2475);
FORCEPROP 1 LAST PATH I20
J 0
(1800 2625);
DISPLAY 0.978723 (1800 2625);
PAINT WHITE (1800 2625);
DISPLAY INVISIBLE (1800 2625);
FORCEADD Q_CAP..1
(1300 3150);
FORCEPROP 1 LAST LOCATION C2425
J 0
(1350 3250);
DISPLAY 0.489362 (1350 3250);
PAINT SKYBLUE (1350 3250);
FORCEPROP 2 LAST $SEC 1
J 0
(1350 3350);
DISPLAY 0.680851 (1350 3350);
PAINT MONO (1350 3350);
DISPLAY INVISIBLE (1350 3350);
FORCEPROP 2 LAST CDS_SEC 1
J 0
(1350 3350);
DISPLAY 1.021277 (1350 3350);
DISPLAY INVISIBLE (1350 3350);
FORCEPROP 1 LASTPIN (1300 3250) $PN 1
J 0
(1310 3230);
DISPLAY 0.489362 (1310 3230);
FORCEPROP 1 LASTPIN (1300 3050) $PN 2
J 0
(1310 3030);
DISPLAY 0.489362 (1310 3030);
FORCEPROP 1 LAST MATERIAL X6S
J 0
(1350 3050);
DISPLAY 0.489362 (1350 3050);
PAINT SKYBLUE (1350 3050);
FORCEPROP 1 LAST TOLERANCE 20%
J 0
(1350 3100);
DISPLAY 0.489362 (1350 3100);
PAINT SKYBLUE (1350 3100);
FORCEPROP 1 LAST VALUE 22UF
J 0
(1350 3200);
DISPLAY 0.489362 (1350 3200);
PAINT SKYBLUE (1350 3200);
FORCEPROP 1 LAST PART_NUMBER CH622KMEB02
J 0
(1350 3000);
DISPLAY 0.489362 (1350 3000);
PAINT SKYBLUE (1350 3000);
FORCEPROP 1 LAST VOLTAGE 4V
J 0
(1350 3150);
DISPLAY 0.489362 (1350 3150);
PAINT SKYBLUE (1350 3150);
FORCEPROP 1 LAST PACK_TYPE C0402
J 0
(1350 2950);
DISPLAY 0.489362 (1350 2950);
PAINT SKYBLUE (1350 2950);
FORCEPROP 2 LAST CDS_LIB pure_quanta
J 0
(1300 3150);
PAINT MONO (1300 3150);
DISPLAY INVISIBLE (1300 3150);
FORCEPROP 1 LAST PATH I21
J 0
(1350 3300);
DISPLAY 0.978723 (1350 3300);
PAINT WHITE (1350 3300);
DISPLAY INVISIBLE (1350 3300);
FORCEADD Q_CAP..1
(1300 3850);
FORCEPROP 1 LAST LOCATION C2424
J 0
(1350 3950);
DISPLAY 0.489362 (1350 3950);
PAINT SKYBLUE (1350 3950);
FORCEPROP 2 LAST $SEC 1
J 0
(1350 4050);
DISPLAY 0.680851 (1350 4050);
PAINT MONO (1350 4050);
DISPLAY INVISIBLE (1350 4050);
FORCEPROP 2 LAST CDS_SEC 1
J 0
(1350 4050);
DISPLAY 1.021277 (1350 4050);
DISPLAY INVISIBLE (1350 4050);
FORCEPROP 1 LASTPIN (1300 3950) $PN 1
J 0
(1310 3930);
DISPLAY 0.489362 (1310 3930);
FORCEPROP 1 LASTPIN (1300 3750) $PN 2
J 0
(1310 3730);
DISPLAY 0.489362 (1310 3730);
FORCEPROP 1 LAST MATERIAL X6S
J 0
(1350 3750);
DISPLAY 0.489362 (1350 3750);
PAINT SKYBLUE (1350 3750);
FORCEPROP 1 LAST TOLERANCE 20%
J 0
(1350 3800);
DISPLAY 0.489362 (1350 3800);
PAINT SKYBLUE (1350 3800);
FORCEPROP 1 LAST VALUE 22UF
J 0
(1350 3900);
DISPLAY 0.489362 (1350 3900);
PAINT SKYBLUE (1350 3900);
FORCEPROP 1 LAST PART_NUMBER CH622KMEB02
J 0
(1350 3700);
DISPLAY 0.489362 (1350 3700);
PAINT SKYBLUE (1350 3700);
FORCEPROP 1 LAST VOLTAGE 4V
J 0
(1350 3850);
DISPLAY 0.489362 (1350 3850);
PAINT SKYBLUE (1350 3850);
FORCEPROP 1 LAST PACK_TYPE C0402
J 0
(1350 3650);
DISPLAY 0.489362 (1350 3650);
PAINT SKYBLUE (1350 3650);
FORCEPROP 2 LAST CDS_LIB pure_quanta
J 0
(1300 3850);
PAINT MONO (1300 3850);
DISPLAY INVISIBLE (1300 3850);
FORCEPROP 1 LAST PATH I22
J 0
(1350 4000);
DISPLAY 0.978723 (1350 4000);
PAINT WHITE (1350 4000);
DISPLAY INVISIBLE (1350 4000);
FORCEADD Q_CAP..1
(1750 3150);
FORCEPROP 1 LAST LOCATION C2432
J 0
(1800 3250);
DISPLAY 0.489362 (1800 3250);
PAINT SKYBLUE (1800 3250);
FORCEPROP 2 LAST $SEC 1
J 0
(1800 3350);
DISPLAY 0.680851 (1800 3350);
PAINT MONO (1800 3350);
DISPLAY INVISIBLE (1800 3350);
FORCEPROP 2 LAST CDS_SEC 1
J 0
(1800 3350);
DISPLAY 1.021277 (1800 3350);
DISPLAY INVISIBLE (1800 3350);
FORCEPROP 1 LASTPIN (1750 3250) $PN 1
J 0
(1760 3230);
DISPLAY 0.489362 (1760 3230);
FORCEPROP 1 LASTPIN (1750 3050) $PN 2
J 0
(1760 3030);
DISPLAY 0.489362 (1760 3030);
FORCEPROP 1 LAST MATERIAL X6S
J 0
(1800 3050);
DISPLAY 0.489362 (1800 3050);
PAINT SKYBLUE (1800 3050);
FORCEPROP 1 LAST TOLERANCE 20%
J 0
(1800 3100);
DISPLAY 0.489362 (1800 3100);
PAINT SKYBLUE (1800 3100);
FORCEPROP 1 LAST VALUE 22UF
J 0
(1800 3200);
DISPLAY 0.489362 (1800 3200);
PAINT SKYBLUE (1800 3200);
FORCEPROP 1 LAST PART_NUMBER CH622KMEB02
J 0
(1800 3000);
DISPLAY 0.489362 (1800 3000);
PAINT SKYBLUE (1800 3000);
FORCEPROP 1 LAST VOLTAGE 4V
J 0
(1800 3150);
DISPLAY 0.489362 (1800 3150);
PAINT SKYBLUE (1800 3150);
FORCEPROP 1 LAST PACK_TYPE C0402
J 0
(1800 2950);
DISPLAY 0.489362 (1800 2950);
PAINT SKYBLUE (1800 2950);
FORCEPROP 2 LAST CDS_LIB pure_quanta
J 0
(1750 3150);
PAINT MONO (1750 3150);
DISPLAY INVISIBLE (1750 3150);
FORCEPROP 1 LAST PATH I23
J 0
(1800 3300);
DISPLAY 0.978723 (1800 3300);
PAINT WHITE (1800 3300);
DISPLAY INVISIBLE (1800 3300);
FORCEADD Q_CAP..1
(1750 3850);
FORCEPROP 1 LAST LOCATION C2431
J 0
(1800 3950);
DISPLAY 0.489362 (1800 3950);
PAINT SKYBLUE (1800 3950);
FORCEPROP 2 LAST $SEC 1
J 0
(1800 4050);
DISPLAY 0.680851 (1800 4050);
PAINT MONO (1800 4050);
DISPLAY INVISIBLE (1800 4050);
FORCEPROP 2 LAST CDS_SEC 1
J 0
(1800 4050);
DISPLAY 1.021277 (1800 4050);
DISPLAY INVISIBLE (1800 4050);
FORCEPROP 1 LASTPIN (1750 3950) $PN 1
J 0
(1760 3930);
DISPLAY 0.489362 (1760 3930);
FORCEPROP 1 LASTPIN (1750 3750) $PN 2
J 0
(1760 3730);
DISPLAY 0.489362 (1760 3730);
FORCEPROP 1 LAST MATERIAL X6S
J 0
(1800 3750);
DISPLAY 0.489362 (1800 3750);
PAINT SKYBLUE (1800 3750);
FORCEPROP 1 LAST TOLERANCE 20%
J 0
(1800 3800);
DISPLAY 0.489362 (1800 3800);
PAINT SKYBLUE (1800 3800);
FORCEPROP 1 LAST VALUE 22UF
J 0
(1800 3900);
DISPLAY 0.489362 (1800 3900);
PAINT SKYBLUE (1800 3900);
FORCEPROP 1 LAST PART_NUMBER CH622KMEB02
J 0
(1800 3700);
DISPLAY 0.489362 (1800 3700);
PAINT SKYBLUE (1800 3700);
FORCEPROP 1 LAST VOLTAGE 4V
J 0
(1800 3850);
DISPLAY 0.489362 (1800 3850);
PAINT SKYBLUE (1800 3850);
FORCEPROP 1 LAST PACK_TYPE C0402
J 0
(1800 3650);
DISPLAY 0.489362 (1800 3650);
PAINT SKYBLUE (1800 3650);
FORCEPROP 2 LAST CDS_LIB pure_quanta
J 0
(1750 3850);
PAINT MONO (1750 3850);
DISPLAY INVISIBLE (1750 3850);
FORCEPROP 1 LAST PATH I24
J 0
(1800 4000);
DISPLAY 0.978723 (1800 4000);
PAINT WHITE (1800 4000);
DISPLAY INVISIBLE (1800 4000);
FORCEADD Q_CAP..1
(2200 1075);
FORCEPROP 1 LAST LOCATION C3916
J 0
(2250 1175);
DISPLAY 0.489362 (2250 1175);
PAINT SKYBLUE (2250 1175);
FORCEPROP 2 LAST $SEC 1
J 0
(2250 1275);
DISPLAY 0.680851 (2250 1275);
PAINT MONO (2250 1275);
DISPLAY INVISIBLE (2250 1275);
FORCEPROP 2 LAST CDS_SEC 1
J 0
(2250 1275);
DISPLAY 1.021277 (2250 1275);
DISPLAY INVISIBLE (2250 1275);
FORCEPROP 1 LASTPIN (2200 1175) $PN 1
J 0
(2210 1155);
DISPLAY 0.489362 (2210 1155);
FORCEPROP 1 LASTPIN (2200 975) $PN 2
J 0
(2210 955);
DISPLAY 0.489362 (2210 955);
FORCEPROP 1 LAST MATERIAL X6S
J 0
(2250 975);
DISPLAY 0.489362 (2250 975);
PAINT SKYBLUE (2250 975);
FORCEPROP 1 LAST TOLERANCE 20%
J 0
(2250 1025);
DISPLAY 0.489362 (2250 1025);
PAINT SKYBLUE (2250 1025);
FORCEPROP 1 LAST VALUE 22UF
J 0
(2250 1125);
DISPLAY 0.489362 (2250 1125);
PAINT SKYBLUE (2250 1125);
FORCEPROP 1 LAST PART_NUMBER CH622KMEB02
J 0
(2250 925);
DISPLAY 0.489362 (2250 925);
PAINT SKYBLUE (2250 925);
FORCEPROP 1 LAST VOLTAGE 4V
J 0
(2250 1075);
DISPLAY 0.489362 (2250 1075);
PAINT SKYBLUE (2250 1075);
FORCEPROP 1 LAST PACK_TYPE C0402
J 0
(2250 875);
DISPLAY 0.489362 (2250 875);
PAINT SKYBLUE (2250 875);
FORCEPROP 2 LAST CDS_LIB pure_quanta
J 0
(2200 1075);
PAINT MONO (2200 1075);
DISPLAY INVISIBLE (2200 1075);
FORCEPROP 1 LAST PATH I25
J 0
(2250 1225);
DISPLAY 0.978723 (2250 1225);
PAINT WHITE (2250 1225);
DISPLAY INVISIBLE (2250 1225);
FORCEADD Q_CAP..1
(2200 1800);
FORCEPROP 1 LAST LOCATION C2441
J 0
(2250 1900);
DISPLAY 0.489362 (2250 1900);
PAINT SKYBLUE (2250 1900);
FORCEPROP 2 LAST $SEC 1
J 0
(2250 2000);
DISPLAY 0.680851 (2250 2000);
PAINT MONO (2250 2000);
DISPLAY INVISIBLE (2250 2000);
FORCEPROP 2 LAST CDS_SEC 1
J 0
(2250 2000);
DISPLAY 1.021277 (2250 2000);
DISPLAY INVISIBLE (2250 2000);
FORCEPROP 1 LASTPIN (2200 1900) $PN 1
J 0
(2210 1880);
DISPLAY 0.489362 (2210 1880);
FORCEPROP 1 LASTPIN (2200 1700) $PN 2
J 0
(2210 1680);
DISPLAY 0.489362 (2210 1680);
FORCEPROP 1 LAST MATERIAL X6S
J 0
(2250 1700);
DISPLAY 0.489362 (2250 1700);
PAINT SKYBLUE (2250 1700);
FORCEPROP 1 LAST TOLERANCE 20%
J 0
(2250 1750);
DISPLAY 0.489362 (2250 1750);
PAINT SKYBLUE (2250 1750);
FORCEPROP 1 LAST VALUE 22UF
J 0
(2250 1850);
DISPLAY 0.489362 (2250 1850);
PAINT SKYBLUE (2250 1850);
FORCEPROP 1 LAST PART_NUMBER CH622KMEB02
J 0
(2250 1650);
DISPLAY 0.489362 (2250 1650);
PAINT SKYBLUE (2250 1650);
FORCEPROP 1 LAST VOLTAGE 4V
J 0
(2250 1800);
DISPLAY 0.489362 (2250 1800);
PAINT SKYBLUE (2250 1800);
FORCEPROP 1 LAST PACK_TYPE C0402
J 0
(2250 1600);
DISPLAY 0.489362 (2250 1600);
PAINT SKYBLUE (2250 1600);
FORCEPROP 2 LAST CDS_LIB pure_quanta
J 0
(2200 1800);
PAINT MONO (2200 1800);
DISPLAY INVISIBLE (2200 1800);
FORCEPROP 1 LAST PATH I26
J 0
(2250 1950);
DISPLAY 0.978723 (2250 1950);
PAINT WHITE (2250 1950);
DISPLAY INVISIBLE (2250 1950);
FORCEADD Q_CAP..1
(2650 1075);
FORCEPROP 1 LAST LOCATION C3917
J 0
(2700 1175);
DISPLAY 0.489362 (2700 1175);
PAINT SKYBLUE (2700 1175);
FORCEPROP 2 LAST $SEC 1
J 0
(2700 1275);
DISPLAY 0.680851 (2700 1275);
PAINT MONO (2700 1275);
DISPLAY INVISIBLE (2700 1275);
FORCEPROP 2 LAST CDS_SEC 1
J 0
(2700 1275);
DISPLAY 1.021277 (2700 1275);
DISPLAY INVISIBLE (2700 1275);
FORCEPROP 1 LASTPIN (2650 1175) $PN 1
J 0
(2660 1155);
DISPLAY 0.489362 (2660 1155);
FORCEPROP 1 LASTPIN (2650 975) $PN 2
J 0
(2660 955);
DISPLAY 0.489362 (2660 955);
FORCEPROP 1 LAST MATERIAL X6S
J 0
(2700 975);
DISPLAY 0.489362 (2700 975);
PAINT SKYBLUE (2700 975);
FORCEPROP 1 LAST TOLERANCE 20%
J 0
(2700 1025);
DISPLAY 0.489362 (2700 1025);
PAINT SKYBLUE (2700 1025);
FORCEPROP 1 LAST VALUE 22UF
J 0
(2700 1125);
DISPLAY 0.489362 (2700 1125);
PAINT SKYBLUE (2700 1125);
FORCEPROP 1 LAST PART_NUMBER CH622KMEB02
J 0
(2700 925);
DISPLAY 0.489362 (2700 925);
PAINT SKYBLUE (2700 925);
FORCEPROP 1 LAST VOLTAGE 4V
J 0
(2700 1075);
DISPLAY 0.489362 (2700 1075);
PAINT SKYBLUE (2700 1075);
FORCEPROP 1 LAST PACK_TYPE C0402
J 0
(2700 875);
DISPLAY 0.489362 (2700 875);
PAINT SKYBLUE (2700 875);
FORCEPROP 2 LAST CDS_LIB pure_quanta
J 0
(2650 1075);
PAINT MONO (2650 1075);
DISPLAY INVISIBLE (2650 1075);
FORCEPROP 1 LAST PATH I27
J 0
(2700 1225);
DISPLAY 0.978723 (2700 1225);
PAINT WHITE (2700 1225);
DISPLAY INVISIBLE (2700 1225);
FORCEADD Q_CAP..1
(2650 1800);
FORCEPROP 1 LAST LOCATION C2448
J 0
(2700 1900);
DISPLAY 0.489362 (2700 1900);
PAINT SKYBLUE (2700 1900);
FORCEPROP 2 LAST $SEC 1
J 0
(2700 2000);
DISPLAY 0.680851 (2700 2000);
PAINT MONO (2700 2000);
DISPLAY INVISIBLE (2700 2000);
FORCEPROP 2 LAST CDS_SEC 1
J 0
(2700 2000);
DISPLAY 1.021277 (2700 2000);
DISPLAY INVISIBLE (2700 2000);
FORCEPROP 1 LASTPIN (2650 1900) $PN 1
J 0
(2660 1880);
DISPLAY 0.489362 (2660 1880);
FORCEPROP 1 LASTPIN (2650 1700) $PN 2
J 0
(2660 1680);
DISPLAY 0.489362 (2660 1680);
FORCEPROP 1 LAST MATERIAL X6S
J 0
(2700 1700);
DISPLAY 0.489362 (2700 1700);
PAINT SKYBLUE (2700 1700);
FORCEPROP 1 LAST TOLERANCE 20%
J 0
(2700 1750);
DISPLAY 0.489362 (2700 1750);
PAINT SKYBLUE (2700 1750);
FORCEPROP 1 LAST VALUE 22UF
J 0
(2700 1850);
DISPLAY 0.489362 (2700 1850);
PAINT SKYBLUE (2700 1850);
FORCEPROP 1 LAST PART_NUMBER CH622KMEB02
J 0
(2700 1650);
DISPLAY 0.489362 (2700 1650);
PAINT SKYBLUE (2700 1650);
FORCEPROP 1 LAST VOLTAGE 4V
J 0
(2700 1800);
DISPLAY 0.489362 (2700 1800);
PAINT SKYBLUE (2700 1800);
FORCEPROP 1 LAST PACK_TYPE C0402
J 0
(2700 1600);
DISPLAY 0.489362 (2700 1600);
PAINT SKYBLUE (2700 1600);
FORCEPROP 2 LAST CDS_LIB pure_quanta
J 0
(2650 1800);
PAINT MONO (2650 1800);
DISPLAY INVISIBLE (2650 1800);
FORCEPROP 1 LAST PATH I28
J 0
(2700 1950);
DISPLAY 0.978723 (2700 1950);
PAINT WHITE (2700 1950);
DISPLAY INVISIBLE (2700 1950);
FORCEADD Q_CAP..1
(3100 1800);
FORCEPROP 1 LAST LOCATION C2455
J 0
(3150 1900);
DISPLAY 0.489362 (3150 1900);
PAINT SKYBLUE (3150 1900);
FORCEPROP 2 LAST $SEC 1
J 0
(3150 2000);
DISPLAY 0.680851 (3150 2000);
PAINT MONO (3150 2000);
DISPLAY INVISIBLE (3150 2000);
FORCEPROP 2 LAST CDS_SEC 1
J 0
(3150 2000);
DISPLAY 1.021277 (3150 2000);
DISPLAY INVISIBLE (3150 2000);
FORCEPROP 1 LASTPIN (3100 1900) $PN 1
J 0
(3110 1880);
DISPLAY 0.489362 (3110 1880);
FORCEPROP 1 LASTPIN (3100 1700) $PN 2
J 0
(3110 1680);
DISPLAY 0.489362 (3110 1680);
FORCEPROP 1 LAST MATERIAL X6S
J 0
(3150 1700);
DISPLAY 0.489362 (3150 1700);
PAINT SKYBLUE (3150 1700);
FORCEPROP 1 LAST TOLERANCE 20%
J 0
(3150 1750);
DISPLAY 0.489362 (3150 1750);
PAINT SKYBLUE (3150 1750);
FORCEPROP 1 LAST VALUE 22UF
J 0
(3150 1850);
DISPLAY 0.489362 (3150 1850);
PAINT SKYBLUE (3150 1850);
FORCEPROP 1 LAST PART_NUMBER CH622KMEB02
J 0
(3150 1650);
DISPLAY 0.489362 (3150 1650);
PAINT SKYBLUE (3150 1650);
FORCEPROP 1 LAST VOLTAGE 4V
J 0
(3150 1800);
DISPLAY 0.489362 (3150 1800);
PAINT SKYBLUE (3150 1800);
FORCEPROP 1 LAST PACK_TYPE C0402
J 0
(3150 1600);
DISPLAY 0.489362 (3150 1600);
PAINT SKYBLUE (3150 1600);
FORCEPROP 2 LAST CDS_LIB pure_quanta
J 0
(3100 1800);
PAINT MONO (3100 1800);
DISPLAY INVISIBLE (3100 1800);
FORCEPROP 1 LAST PATH I29
J 0
(3150 1950);
DISPLAY 0.978723 (3150 1950);
PAINT WHITE (3150 1950);
DISPLAY INVISIBLE (3150 1950);
FORCEADD Q_CAP..1
(400 1800);
FORCEPROP 1 LAST LOCATION C2413
J 0
(450 1900);
DISPLAY 0.489362 (450 1900);
PAINT SKYBLUE (450 1900);
FORCEPROP 2 LAST $SEC 1
J 0
(450 2000);
DISPLAY 0.680851 (450 2000);
PAINT MONO (450 2000);
DISPLAY INVISIBLE (450 2000);
FORCEPROP 2 LAST CDS_SEC 1
J 0
(450 2000);
DISPLAY 1.021277 (450 2000);
DISPLAY INVISIBLE (450 2000);
FORCEPROP 1 LASTPIN (400 1900) $PN 1
J 0
(410 1880);
DISPLAY 0.489362 (410 1880);
FORCEPROP 1 LASTPIN (400 1700) $PN 2
J 0
(410 1680);
DISPLAY 0.489362 (410 1680);
FORCEPROP 1 LAST MATERIAL X6S
J 0
(450 1700);
DISPLAY 0.489362 (450 1700);
PAINT SKYBLUE (450 1700);
FORCEPROP 1 LAST TOLERANCE 20%
J 0
(450 1750);
DISPLAY 0.489362 (450 1750);
PAINT SKYBLUE (450 1750);
FORCEPROP 1 LAST VALUE 22UF
J 0
(450 1850);
DISPLAY 0.489362 (450 1850);
PAINT SKYBLUE (450 1850);
FORCEPROP 1 LAST PART_NUMBER CH622KMEB02
J 0
(450 1650);
DISPLAY 0.489362 (450 1650);
PAINT SKYBLUE (450 1650);
FORCEPROP 1 LAST VOLTAGE 4V
J 0
(450 1800);
DISPLAY 0.489362 (450 1800);
PAINT SKYBLUE (450 1800);
FORCEPROP 1 LAST PACK_TYPE C0402
J 0
(450 1600);
DISPLAY 0.489362 (450 1600);
PAINT SKYBLUE (450 1600);
FORCEPROP 2 LAST CDS_LIB pure_quanta
J 0
(400 1800);
PAINT MONO (400 1800);
DISPLAY INVISIBLE (400 1800);
FORCEPROP 1 LAST PATH I3
J 0
(450 1950);
DISPLAY 0.978723 (450 1950);
PAINT WHITE (450 1950);
DISPLAY INVISIBLE (450 1950);
FORCEADD Q_CAP..1
(3100 1075);
FORCEPROP 1 LAST LOCATION C3918
J 0
(3150 1175);
DISPLAY 0.489362 (3150 1175);
PAINT SKYBLUE (3150 1175);
FORCEPROP 2 LAST $SEC 1
J 0
(3150 1275);
DISPLAY 0.680851 (3150 1275);
PAINT MONO (3150 1275);
DISPLAY INVISIBLE (3150 1275);
FORCEPROP 2 LAST CDS_SEC 1
J 0
(3150 1275);
DISPLAY 1.021277 (3150 1275);
DISPLAY INVISIBLE (3150 1275);
FORCEPROP 1 LASTPIN (3100 1175) $PN 1
J 0
(3110 1155);
DISPLAY 0.489362 (3110 1155);
FORCEPROP 1 LASTPIN (3100 975) $PN 2
J 0
(3110 955);
DISPLAY 0.489362 (3110 955);
FORCEPROP 1 LAST MATERIAL X6S
J 0
(3150 975);
DISPLAY 0.489362 (3150 975);
PAINT SKYBLUE (3150 975);
FORCEPROP 1 LAST TOLERANCE 20%
J 0
(3150 1025);
DISPLAY 0.489362 (3150 1025);
PAINT SKYBLUE (3150 1025);
FORCEPROP 1 LAST VALUE 22UF
J 0
(3150 1125);
DISPLAY 0.489362 (3150 1125);
PAINT SKYBLUE (3150 1125);
FORCEPROP 1 LAST PART_NUMBER CH622KMEB02
J 0
(3150 925);
DISPLAY 0.489362 (3150 925);
PAINT SKYBLUE (3150 925);
FORCEPROP 1 LAST VOLTAGE 4V
J 0
(3150 1075);
DISPLAY 0.489362 (3150 1075);
PAINT SKYBLUE (3150 1075);
FORCEPROP 1 LAST PACK_TYPE C0402
J 0
(3150 875);
DISPLAY 0.489362 (3150 875);
PAINT SKYBLUE (3150 875);
FORCEPROP 2 LAST CDS_LIB pure_quanta
J 0
(3100 1075);
PAINT MONO (3100 1075);
DISPLAY INVISIBLE (3100 1075);
FORCEPROP 1 LAST PATH I30
J 0
(3150 1225);
DISPLAY 0.978723 (3150 1225);
PAINT WHITE (3150 1225);
DISPLAY INVISIBLE (3150 1225);
FORCEADD UNIVERSAL_GND..1
(3100 700);
FORCEPROP 3 LASTPIN (3100 750) SIG_NAME GND\g
J 0
(3110 760);
DISPLAY 0.659574 (3110 760);
PAINT MONO (3110 760);
DISPLAY INVISIBLE (3110 760);
FORCEPROP 2 LAST CDS_LIB pure_quanta_power
J 0
(3100 700);
PAINT MONO (3100 700);
DISPLAY INVISIBLE (3100 700);
FORCEPROP 1 LAST PATH I31
J 0
(3175 700);
DISPLAY 0.872340 (3175 700);
PAINT AQUA (3175 700);
DISPLAY INVISIBLE (3175 700);
FORCEPROP 1 LAST HDL_POWER GND
J 1
(3125 625);
DISPLAY 0.872340 (3125 625);
PAINT GREEN (3125 625);
DISPLAY INVISIBLE (3125 625);
FORCEADD Q_CAP..1
(3550 1800);
FORCEPROP 1 LAST LOCATION C2462
J 0
(3600 1900);
DISPLAY 0.489362 (3600 1900);
PAINT SKYBLUE (3600 1900);
FORCEPROP 2 LAST $SEC 1
J 0
(3600 2000);
DISPLAY 0.680851 (3600 2000);
PAINT MONO (3600 2000);
DISPLAY INVISIBLE (3600 2000);
FORCEPROP 2 LAST CDS_SEC 1
J 0
(3600 2000);
DISPLAY 1.021277 (3600 2000);
DISPLAY INVISIBLE (3600 2000);
FORCEPROP 1 LASTPIN (3550 1900) $PN 1
J 0
(3560 1880);
DISPLAY 0.489362 (3560 1880);
FORCEPROP 1 LASTPIN (3550 1700) $PN 2
J 0
(3560 1680);
DISPLAY 0.489362 (3560 1680);
FORCEPROP 1 LAST MATERIAL X6S
J 0
(3600 1700);
DISPLAY 0.489362 (3600 1700);
PAINT SKYBLUE (3600 1700);
FORCEPROP 1 LAST TOLERANCE 20%
J 0
(3600 1750);
DISPLAY 0.489362 (3600 1750);
PAINT SKYBLUE (3600 1750);
FORCEPROP 1 LAST VALUE 22UF
J 0
(3600 1850);
DISPLAY 0.489362 (3600 1850);
PAINT SKYBLUE (3600 1850);
FORCEPROP 1 LAST PART_NUMBER CH622KMEB02
J 0
(3600 1650);
DISPLAY 0.489362 (3600 1650);
PAINT SKYBLUE (3600 1650);
FORCEPROP 1 LAST VOLTAGE 4V
J 0
(3600 1800);
DISPLAY 0.489362 (3600 1800);
PAINT SKYBLUE (3600 1800);
FORCEPROP 1 LAST PACK_TYPE C0402
J 0
(3600 1600);
DISPLAY 0.489362 (3600 1600);
PAINT SKYBLUE (3600 1600);
FORCEPROP 2 LAST CDS_LIB pure_quanta
J 0
(3550 1800);
PAINT MONO (3550 1800);
DISPLAY INVISIBLE (3550 1800);
FORCEPROP 1 LAST PATH I32
J 0
(3600 1950);
DISPLAY 0.978723 (3600 1950);
PAINT WHITE (3600 1950);
DISPLAY INVISIBLE (3600 1950);
FORCEADD Q_CAP..1
(4000 1800);
FORCEPROP 1 LAST LOCATION C2469
J 0
(4050 1900);
DISPLAY 0.489362 (4050 1900);
PAINT SKYBLUE (4050 1900);
FORCEPROP 2 LAST $SEC 1
J 0
(4050 2000);
DISPLAY 0.680851 (4050 2000);
PAINT MONO (4050 2000);
DISPLAY INVISIBLE (4050 2000);
FORCEPROP 2 LAST CDS_SEC 1
J 0
(4050 2000);
DISPLAY 1.021277 (4050 2000);
DISPLAY INVISIBLE (4050 2000);
FORCEPROP 1 LASTPIN (4000 1900) $PN 1
J 0
(4010 1880);
DISPLAY 0.489362 (4010 1880);
FORCEPROP 1 LASTPIN (4000 1700) $PN 2
J 0
(4010 1680);
DISPLAY 0.489362 (4010 1680);
FORCEPROP 1 LAST MATERIAL X6S
J 0
(4050 1700);
DISPLAY 0.489362 (4050 1700);
PAINT SKYBLUE (4050 1700);
FORCEPROP 1 LAST TOLERANCE 20%
J 0
(4050 1750);
DISPLAY 0.489362 (4050 1750);
PAINT SKYBLUE (4050 1750);
FORCEPROP 1 LAST VALUE 22UF
J 0
(4050 1850);
DISPLAY 0.489362 (4050 1850);
PAINT SKYBLUE (4050 1850);
FORCEPROP 1 LAST PART_NUMBER CH622KMEB02
J 0
(4050 1650);
DISPLAY 0.489362 (4050 1650);
PAINT SKYBLUE (4050 1650);
FORCEPROP 1 LAST VOLTAGE 4V
J 0
(4050 1800);
DISPLAY 0.489362 (4050 1800);
PAINT SKYBLUE (4050 1800);
FORCEPROP 1 LAST PACK_TYPE C0402
J 0
(4050 1600);
DISPLAY 0.489362 (4050 1600);
PAINT SKYBLUE (4050 1600);
FORCEPROP 2 LAST CDS_LIB pure_quanta
J 0
(4000 1800);
PAINT MONO (4000 1800);
DISPLAY INVISIBLE (4000 1800);
FORCEPROP 1 LAST PATH I33
J 0
(4050 1950);
DISPLAY 0.978723 (4050 1950);
PAINT WHITE (4050 1950);
DISPLAY INVISIBLE (4050 1950);
FORCEADD Q_CAP..1
(2200 2475);
FORCEPROP 1 LAST LOCATION C2440
J 0
(2250 2575);
DISPLAY 0.489362 (2250 2575);
PAINT SKYBLUE (2250 2575);
FORCEPROP 2 LAST $SEC 1
J 0
(2250 2675);
DISPLAY 0.680851 (2250 2675);
PAINT MONO (2250 2675);
DISPLAY INVISIBLE (2250 2675);
FORCEPROP 2 LAST CDS_SEC 1
J 0
(2250 2675);
DISPLAY 1.021277 (2250 2675);
DISPLAY INVISIBLE (2250 2675);
FORCEPROP 1 LASTPIN (2200 2575) $PN 1
J 0
(2210 2555);
DISPLAY 0.489362 (2210 2555);
FORCEPROP 1 LASTPIN (2200 2375) $PN 2
J 0
(2210 2355);
DISPLAY 0.489362 (2210 2355);
FORCEPROP 1 LAST MATERIAL X6S
J 0
(2250 2375);
DISPLAY 0.489362 (2250 2375);
PAINT SKYBLUE (2250 2375);
FORCEPROP 1 LAST TOLERANCE 20%
J 0
(2250 2425);
DISPLAY 0.489362 (2250 2425);
PAINT SKYBLUE (2250 2425);
FORCEPROP 1 LAST VALUE 22UF
J 0
(2250 2525);
DISPLAY 0.489362 (2250 2525);
PAINT SKYBLUE (2250 2525);
FORCEPROP 1 LAST PART_NUMBER CH622KMEB02
J 0
(2250 2325);
DISPLAY 0.489362 (2250 2325);
PAINT SKYBLUE (2250 2325);
FORCEPROP 1 LAST VOLTAGE 4V
J 0
(2250 2475);
DISPLAY 0.489362 (2250 2475);
PAINT SKYBLUE (2250 2475);
FORCEPROP 1 LAST PACK_TYPE C0402
J 0
(2250 2275);
DISPLAY 0.489362 (2250 2275);
PAINT SKYBLUE (2250 2275);
FORCEPROP 2 LAST CDS_LIB pure_quanta
J 0
(2200 2475);
PAINT MONO (2200 2475);
DISPLAY INVISIBLE (2200 2475);
FORCEPROP 1 LAST PATH I34
J 0
(2250 2625);
DISPLAY 0.978723 (2250 2625);
PAINT WHITE (2250 2625);
DISPLAY INVISIBLE (2250 2625);
FORCEADD Q_CAP..1
(2650 2475);
FORCEPROP 1 LAST LOCATION C2447
J 0
(2700 2575);
DISPLAY 0.489362 (2700 2575);
PAINT SKYBLUE (2700 2575);
FORCEPROP 2 LAST $SEC 1
J 0
(2700 2675);
DISPLAY 0.680851 (2700 2675);
PAINT MONO (2700 2675);
DISPLAY INVISIBLE (2700 2675);
FORCEPROP 2 LAST CDS_SEC 1
J 0
(2700 2675);
DISPLAY 1.021277 (2700 2675);
DISPLAY INVISIBLE (2700 2675);
FORCEPROP 1 LASTPIN (2650 2575) $PN 1
J 0
(2660 2555);
DISPLAY 0.489362 (2660 2555);
FORCEPROP 1 LASTPIN (2650 2375) $PN 2
J 0
(2660 2355);
DISPLAY 0.489362 (2660 2355);
FORCEPROP 1 LAST MATERIAL X6S
J 0
(2700 2375);
DISPLAY 0.489362 (2700 2375);
PAINT SKYBLUE (2700 2375);
FORCEPROP 1 LAST TOLERANCE 20%
J 0
(2700 2425);
DISPLAY 0.489362 (2700 2425);
PAINT SKYBLUE (2700 2425);
FORCEPROP 1 LAST VALUE 22UF
J 0
(2700 2525);
DISPLAY 0.489362 (2700 2525);
PAINT SKYBLUE (2700 2525);
FORCEPROP 1 LAST PART_NUMBER CH622KMEB02
J 0
(2700 2325);
DISPLAY 0.489362 (2700 2325);
PAINT SKYBLUE (2700 2325);
FORCEPROP 1 LAST VOLTAGE 4V
J 0
(2700 2475);
DISPLAY 0.489362 (2700 2475);
PAINT SKYBLUE (2700 2475);
FORCEPROP 1 LAST PACK_TYPE C0402
J 0
(2700 2275);
DISPLAY 0.489362 (2700 2275);
PAINT SKYBLUE (2700 2275);
FORCEPROP 2 LAST CDS_LIB pure_quanta
J 0
(2650 2475);
PAINT MONO (2650 2475);
DISPLAY INVISIBLE (2650 2475);
FORCEPROP 1 LAST PATH I35
J 0
(2700 2625);
DISPLAY 0.978723 (2700 2625);
PAINT WHITE (2700 2625);
DISPLAY INVISIBLE (2700 2625);
FORCEADD Q_CAP..1
(2200 3150);
FORCEPROP 1 LAST LOCATION C2439
J 0
(2250 3250);
DISPLAY 0.489362 (2250 3250);
PAINT SKYBLUE (2250 3250);
FORCEPROP 2 LAST $SEC 1
J 0
(2250 3350);
DISPLAY 0.680851 (2250 3350);
PAINT MONO (2250 3350);
DISPLAY INVISIBLE (2250 3350);
FORCEPROP 2 LAST CDS_SEC 1
J 0
(2250 3350);
DISPLAY 1.021277 (2250 3350);
DISPLAY INVISIBLE (2250 3350);
FORCEPROP 1 LASTPIN (2200 3250) $PN 1
J 0
(2210 3230);
DISPLAY 0.489362 (2210 3230);
FORCEPROP 1 LASTPIN (2200 3050) $PN 2
J 0
(2210 3030);
DISPLAY 0.489362 (2210 3030);
FORCEPROP 1 LAST MATERIAL X6S
J 0
(2250 3050);
DISPLAY 0.489362 (2250 3050);
PAINT SKYBLUE (2250 3050);
FORCEPROP 1 LAST TOLERANCE 20%
J 0
(2250 3100);
DISPLAY 0.489362 (2250 3100);
PAINT SKYBLUE (2250 3100);
FORCEPROP 1 LAST VALUE 22UF
J 0
(2250 3200);
DISPLAY 0.489362 (2250 3200);
PAINT SKYBLUE (2250 3200);
FORCEPROP 1 LAST PART_NUMBER CH622KMEB02
J 0
(2250 3000);
DISPLAY 0.489362 (2250 3000);
PAINT SKYBLUE (2250 3000);
FORCEPROP 1 LAST VOLTAGE 4V
J 0
(2250 3150);
DISPLAY 0.489362 (2250 3150);
PAINT SKYBLUE (2250 3150);
FORCEPROP 1 LAST PACK_TYPE C0402
J 0
(2250 2950);
DISPLAY 0.489362 (2250 2950);
PAINT SKYBLUE (2250 2950);
FORCEPROP 2 LAST CDS_LIB pure_quanta
J 0
(2200 3150);
PAINT MONO (2200 3150);
DISPLAY INVISIBLE (2200 3150);
FORCEPROP 1 LAST PATH I36
J 0
(2250 3300);
DISPLAY 0.978723 (2250 3300);
PAINT WHITE (2250 3300);
DISPLAY INVISIBLE (2250 3300);
FORCEADD Q_CAP..1
(2200 3850);
FORCEPROP 1 LAST LOCATION C2438
J 0
(2250 3950);
DISPLAY 0.489362 (2250 3950);
PAINT SKYBLUE (2250 3950);
FORCEPROP 2 LAST $SEC 1
J 0
(2250 4050);
DISPLAY 0.680851 (2250 4050);
PAINT MONO (2250 4050);
DISPLAY INVISIBLE (2250 4050);
FORCEPROP 2 LAST CDS_SEC 1
J 0
(2250 4050);
DISPLAY 1.021277 (2250 4050);
DISPLAY INVISIBLE (2250 4050);
FORCEPROP 1 LASTPIN (2200 3950) $PN 1
J 0
(2210 3930);
DISPLAY 0.489362 (2210 3930);
FORCEPROP 1 LASTPIN (2200 3750) $PN 2
J 0
(2210 3730);
DISPLAY 0.489362 (2210 3730);
FORCEPROP 1 LAST MATERIAL X6S
J 0
(2250 3750);
DISPLAY 0.489362 (2250 3750);
PAINT SKYBLUE (2250 3750);
FORCEPROP 1 LAST TOLERANCE 20%
J 0
(2250 3800);
DISPLAY 0.489362 (2250 3800);
PAINT SKYBLUE (2250 3800);
FORCEPROP 1 LAST VALUE 22UF
J 0
(2250 3900);
DISPLAY 0.489362 (2250 3900);
PAINT SKYBLUE (2250 3900);
FORCEPROP 1 LAST PART_NUMBER CH622KMEB02
J 0
(2250 3700);
DISPLAY 0.489362 (2250 3700);
PAINT SKYBLUE (2250 3700);
FORCEPROP 1 LAST VOLTAGE 4V
J 0
(2250 3850);
DISPLAY 0.489362 (2250 3850);
PAINT SKYBLUE (2250 3850);
FORCEPROP 1 LAST PACK_TYPE C0402
J 0
(2250 3650);
DISPLAY 0.489362 (2250 3650);
PAINT SKYBLUE (2250 3650);
FORCEPROP 2 LAST CDS_LIB pure_quanta
J 0
(2200 3850);
PAINT MONO (2200 3850);
DISPLAY INVISIBLE (2200 3850);
FORCEPROP 1 LAST PATH I37
J 0
(2250 4000);
DISPLAY 0.978723 (2250 4000);
PAINT WHITE (2250 4000);
DISPLAY INVISIBLE (2250 4000);
FORCEADD Q_CAP..1
(2650 3150);
FORCEPROP 1 LAST LOCATION C2446
J 0
(2700 3250);
DISPLAY 0.489362 (2700 3250);
PAINT SKYBLUE (2700 3250);
FORCEPROP 2 LAST $SEC 1
J 0
(2700 3350);
DISPLAY 0.680851 (2700 3350);
PAINT MONO (2700 3350);
DISPLAY INVISIBLE (2700 3350);
FORCEPROP 2 LAST CDS_SEC 1
J 0
(2700 3350);
DISPLAY 1.021277 (2700 3350);
DISPLAY INVISIBLE (2700 3350);
FORCEPROP 1 LASTPIN (2650 3250) $PN 1
J 0
(2660 3230);
DISPLAY 0.489362 (2660 3230);
FORCEPROP 1 LASTPIN (2650 3050) $PN 2
J 0
(2660 3030);
DISPLAY 0.489362 (2660 3030);
FORCEPROP 1 LAST MATERIAL X6S
J 0
(2700 3050);
DISPLAY 0.489362 (2700 3050);
PAINT SKYBLUE (2700 3050);
FORCEPROP 1 LAST TOLERANCE 20%
J 0
(2700 3100);
DISPLAY 0.489362 (2700 3100);
PAINT SKYBLUE (2700 3100);
FORCEPROP 1 LAST VALUE 22UF
J 0
(2700 3200);
DISPLAY 0.489362 (2700 3200);
PAINT SKYBLUE (2700 3200);
FORCEPROP 1 LAST PART_NUMBER CH622KMEB02
J 0
(2700 3000);
DISPLAY 0.489362 (2700 3000);
PAINT SKYBLUE (2700 3000);
FORCEPROP 1 LAST VOLTAGE 4V
J 0
(2700 3150);
DISPLAY 0.489362 (2700 3150);
PAINT SKYBLUE (2700 3150);
FORCEPROP 1 LAST PACK_TYPE C0402
J 0
(2700 2950);
DISPLAY 0.489362 (2700 2950);
PAINT SKYBLUE (2700 2950);
FORCEPROP 2 LAST CDS_LIB pure_quanta
J 0
(2650 3150);
PAINT MONO (2650 3150);
DISPLAY INVISIBLE (2650 3150);
FORCEPROP 1 LAST PATH I38
J 0
(2700 3300);
DISPLAY 0.978723 (2700 3300);
PAINT WHITE (2700 3300);
DISPLAY INVISIBLE (2700 3300);
FORCEADD Q_CAP..1
(2650 3850);
FORCEPROP 1 LAST LOCATION C2445
J 0
(2700 3950);
DISPLAY 0.489362 (2700 3950);
PAINT SKYBLUE (2700 3950);
FORCEPROP 2 LAST $SEC 1
J 0
(2700 4050);
DISPLAY 0.680851 (2700 4050);
PAINT MONO (2700 4050);
DISPLAY INVISIBLE (2700 4050);
FORCEPROP 2 LAST CDS_SEC 1
J 0
(2700 4050);
DISPLAY 1.021277 (2700 4050);
DISPLAY INVISIBLE (2700 4050);
FORCEPROP 1 LASTPIN (2650 3950) $PN 1
J 0
(2660 3930);
DISPLAY 0.489362 (2660 3930);
FORCEPROP 1 LASTPIN (2650 3750) $PN 2
J 0
(2660 3730);
DISPLAY 0.489362 (2660 3730);
FORCEPROP 1 LAST MATERIAL X6S
J 0
(2700 3750);
DISPLAY 0.489362 (2700 3750);
PAINT SKYBLUE (2700 3750);
FORCEPROP 1 LAST TOLERANCE 20%
J 0
(2700 3800);
DISPLAY 0.489362 (2700 3800);
PAINT SKYBLUE (2700 3800);
FORCEPROP 1 LAST VALUE 22UF
J 0
(2700 3900);
DISPLAY 0.489362 (2700 3900);
PAINT SKYBLUE (2700 3900);
FORCEPROP 1 LAST PART_NUMBER CH622KMEB02
J 0
(2700 3700);
DISPLAY 0.489362 (2700 3700);
PAINT SKYBLUE (2700 3700);
FORCEPROP 1 LAST VOLTAGE 4V
J 0
(2700 3850);
DISPLAY 0.489362 (2700 3850);
PAINT SKYBLUE (2700 3850);
FORCEPROP 1 LAST PACK_TYPE C0402
J 0
(2700 3650);
DISPLAY 0.489362 (2700 3650);
PAINT SKYBLUE (2700 3650);
FORCEPROP 2 LAST CDS_LIB pure_quanta
J 0
(2650 3850);
PAINT MONO (2650 3850);
DISPLAY INVISIBLE (2650 3850);
FORCEPROP 1 LAST PATH I39
J 0
(2700 4000);
DISPLAY 0.978723 (2700 4000);
PAINT WHITE (2700 4000);
DISPLAY INVISIBLE (2700 4000);
FORCEADD Q_CAP..1
(850 1075);
FORCEPROP 1 LAST LOCATION C3913
J 0
(900 1175);
DISPLAY 0.489362 (900 1175);
PAINT SKYBLUE (900 1175);
FORCEPROP 2 LAST $SEC 1
J 0
(900 1275);
DISPLAY 0.680851 (900 1275);
PAINT MONO (900 1275);
DISPLAY INVISIBLE (900 1275);
FORCEPROP 2 LAST CDS_SEC 1
J 0
(900 1275);
DISPLAY 1.021277 (900 1275);
DISPLAY INVISIBLE (900 1275);
FORCEPROP 1 LASTPIN (850 1175) $PN 1
J 0
(860 1155);
DISPLAY 0.489362 (860 1155);
FORCEPROP 1 LASTPIN (850 975) $PN 2
J 0
(860 955);
DISPLAY 0.489362 (860 955);
FORCEPROP 1 LAST MATERIAL X6S
J 0
(900 975);
DISPLAY 0.489362 (900 975);
PAINT SKYBLUE (900 975);
FORCEPROP 1 LAST TOLERANCE 20%
J 0
(900 1025);
DISPLAY 0.489362 (900 1025);
PAINT SKYBLUE (900 1025);
FORCEPROP 1 LAST VALUE 22UF
J 0
(900 1125);
DISPLAY 0.489362 (900 1125);
PAINT SKYBLUE (900 1125);
FORCEPROP 1 LAST PART_NUMBER CH622KMEB02
J 0
(900 925);
DISPLAY 0.489362 (900 925);
PAINT SKYBLUE (900 925);
FORCEPROP 1 LAST VOLTAGE 4V
J 0
(900 1075);
DISPLAY 0.489362 (900 1075);
PAINT SKYBLUE (900 1075);
FORCEPROP 1 LAST PACK_TYPE C0402
J 0
(900 875);
DISPLAY 0.489362 (900 875);
PAINT SKYBLUE (900 875);
FORCEPROP 2 LAST CDS_LIB pure_quanta
J 0
(850 1075);
PAINT MONO (850 1075);
DISPLAY INVISIBLE (850 1075);
FORCEPROP 1 LAST PATH I4
J 0
(900 1225);
DISPLAY 0.978723 (900 1225);
PAINT WHITE (900 1225);
DISPLAY INVISIBLE (900 1225);
FORCEADD Q_CAP..1
(3100 3850);
FORCEPROP 1 LAST LOCATION C2452
J 0
(3150 3950);
DISPLAY 0.489362 (3150 3950);
PAINT SKYBLUE (3150 3950);
FORCEPROP 2 LAST $SEC 1
J 0
(3150 4050);
DISPLAY 0.680851 (3150 4050);
PAINT MONO (3150 4050);
DISPLAY INVISIBLE (3150 4050);
FORCEPROP 2 LAST CDS_SEC 1
J 0
(3150 4050);
DISPLAY 1.021277 (3150 4050);
DISPLAY INVISIBLE (3150 4050);
FORCEPROP 1 LASTPIN (3100 3950) $PN 1
J 0
(3110 3930);
DISPLAY 0.489362 (3110 3930);
FORCEPROP 1 LASTPIN (3100 3750) $PN 2
J 0
(3110 3730);
DISPLAY 0.489362 (3110 3730);
FORCEPROP 1 LAST MATERIAL X6S
J 0
(3150 3750);
DISPLAY 0.489362 (3150 3750);
PAINT SKYBLUE (3150 3750);
FORCEPROP 1 LAST TOLERANCE 20%
J 0
(3150 3800);
DISPLAY 0.489362 (3150 3800);
PAINT SKYBLUE (3150 3800);
FORCEPROP 1 LAST VALUE 22UF
J 0
(3150 3900);
DISPLAY 0.489362 (3150 3900);
PAINT SKYBLUE (3150 3900);
FORCEPROP 1 LAST PART_NUMBER CH622KMEB02
J 0
(3150 3700);
DISPLAY 0.489362 (3150 3700);
PAINT SKYBLUE (3150 3700);
FORCEPROP 1 LAST VOLTAGE 4V
J 0
(3150 3850);
DISPLAY 0.489362 (3150 3850);
PAINT SKYBLUE (3150 3850);
FORCEPROP 1 LAST PACK_TYPE C0402
J 0
(3150 3650);
DISPLAY 0.489362 (3150 3650);
PAINT SKYBLUE (3150 3650);
FORCEPROP 2 LAST CDS_LIB pure_quanta
J 0
(3100 3850);
PAINT MONO (3100 3850);
DISPLAY INVISIBLE (3100 3850);
FORCEPROP 1 LAST PATH I40
J 0
(3150 4000);
DISPLAY 0.978723 (3150 4000);
PAINT WHITE (3150 4000);
DISPLAY INVISIBLE (3150 4000);
FORCEADD Q_CAP..1
(3100 3150);
FORCEPROP 1 LAST LOCATION C2453
J 0
(3150 3250);
DISPLAY 0.489362 (3150 3250);
PAINT SKYBLUE (3150 3250);
FORCEPROP 2 LAST $SEC 1
J 0
(3150 3350);
DISPLAY 0.680851 (3150 3350);
PAINT MONO (3150 3350);
DISPLAY INVISIBLE (3150 3350);
FORCEPROP 2 LAST CDS_SEC 1
J 0
(3150 3350);
DISPLAY 1.021277 (3150 3350);
DISPLAY INVISIBLE (3150 3350);
FORCEPROP 1 LASTPIN (3100 3250) $PN 1
J 0
(3110 3230);
DISPLAY 0.489362 (3110 3230);
FORCEPROP 1 LASTPIN (3100 3050) $PN 2
J 0
(3110 3030);
DISPLAY 0.489362 (3110 3030);
FORCEPROP 1 LAST MATERIAL X6S
J 0
(3150 3050);
DISPLAY 0.489362 (3150 3050);
PAINT SKYBLUE (3150 3050);
FORCEPROP 1 LAST TOLERANCE 20%
J 0
(3150 3100);
DISPLAY 0.489362 (3150 3100);
PAINT SKYBLUE (3150 3100);
FORCEPROP 1 LAST VALUE 22UF
J 0
(3150 3200);
DISPLAY 0.489362 (3150 3200);
PAINT SKYBLUE (3150 3200);
FORCEPROP 1 LAST PART_NUMBER CH622KMEB02
J 0
(3150 3000);
DISPLAY 0.489362 (3150 3000);
PAINT SKYBLUE (3150 3000);
FORCEPROP 1 LAST VOLTAGE 4V
J 0
(3150 3150);
DISPLAY 0.489362 (3150 3150);
PAINT SKYBLUE (3150 3150);
FORCEPROP 1 LAST PACK_TYPE C0402
J 0
(3150 2950);
DISPLAY 0.489362 (3150 2950);
PAINT SKYBLUE (3150 2950);
FORCEPROP 2 LAST CDS_LIB pure_quanta
J 0
(3100 3150);
PAINT MONO (3100 3150);
DISPLAY INVISIBLE (3100 3150);
FORCEPROP 1 LAST PATH I41
J 0
(3150 3300);
DISPLAY 0.978723 (3150 3300);
PAINT WHITE (3150 3300);
DISPLAY INVISIBLE (3150 3300);
FORCEADD Q_CAP..1
(3100 2475);
FORCEPROP 1 LAST LOCATION C2454
J 0
(3150 2575);
DISPLAY 0.489362 (3150 2575);
PAINT SKYBLUE (3150 2575);
FORCEPROP 2 LAST $SEC 1
J 0
(3150 2675);
DISPLAY 0.680851 (3150 2675);
PAINT MONO (3150 2675);
DISPLAY INVISIBLE (3150 2675);
FORCEPROP 2 LAST CDS_SEC 1
J 0
(3150 2675);
DISPLAY 1.021277 (3150 2675);
DISPLAY INVISIBLE (3150 2675);
FORCEPROP 1 LASTPIN (3100 2575) $PN 1
J 0
(3110 2555);
DISPLAY 0.489362 (3110 2555);
FORCEPROP 1 LASTPIN (3100 2375) $PN 2
J 0
(3110 2355);
DISPLAY 0.489362 (3110 2355);
FORCEPROP 1 LAST MATERIAL X6S
J 0
(3150 2375);
DISPLAY 0.489362 (3150 2375);
PAINT SKYBLUE (3150 2375);
FORCEPROP 1 LAST TOLERANCE 20%
J 0
(3150 2425);
DISPLAY 0.489362 (3150 2425);
PAINT SKYBLUE (3150 2425);
FORCEPROP 1 LAST VALUE 22UF
J 0
(3150 2525);
DISPLAY 0.489362 (3150 2525);
PAINT SKYBLUE (3150 2525);
FORCEPROP 1 LAST PART_NUMBER CH622KMEB02
J 0
(3150 2325);
DISPLAY 0.489362 (3150 2325);
PAINT SKYBLUE (3150 2325);
FORCEPROP 1 LAST VOLTAGE 4V
J 0
(3150 2475);
DISPLAY 0.489362 (3150 2475);
PAINT SKYBLUE (3150 2475);
FORCEPROP 1 LAST PACK_TYPE C0402
J 0
(3150 2275);
DISPLAY 0.489362 (3150 2275);
PAINT SKYBLUE (3150 2275);
FORCEPROP 2 LAST CDS_LIB pure_quanta
J 0
(3100 2475);
PAINT MONO (3100 2475);
DISPLAY INVISIBLE (3100 2475);
FORCEPROP 1 LAST PATH I42
J 0
(3150 2625);
DISPLAY 0.978723 (3150 2625);
PAINT WHITE (3150 2625);
DISPLAY INVISIBLE (3150 2625);
FORCEADD Q_CAP..1
(3550 2475);
FORCEPROP 1 LAST LOCATION C2461
J 0
(3600 2575);
DISPLAY 0.489362 (3600 2575);
PAINT SKYBLUE (3600 2575);
FORCEPROP 2 LAST $SEC 1
J 0
(3600 2675);
DISPLAY 0.680851 (3600 2675);
PAINT MONO (3600 2675);
DISPLAY INVISIBLE (3600 2675);
FORCEPROP 2 LAST CDS_SEC 1
J 0
(3600 2675);
DISPLAY 1.021277 (3600 2675);
DISPLAY INVISIBLE (3600 2675);
FORCEPROP 1 LASTPIN (3550 2575) $PN 1
J 0
(3560 2555);
DISPLAY 0.489362 (3560 2555);
FORCEPROP 1 LASTPIN (3550 2375) $PN 2
J 0
(3560 2355);
DISPLAY 0.489362 (3560 2355);
FORCEPROP 1 LAST MATERIAL X6S
J 0
(3600 2375);
DISPLAY 0.489362 (3600 2375);
PAINT SKYBLUE (3600 2375);
FORCEPROP 1 LAST TOLERANCE 20%
J 0
(3600 2425);
DISPLAY 0.489362 (3600 2425);
PAINT SKYBLUE (3600 2425);
FORCEPROP 1 LAST VALUE 22UF
J 0
(3600 2525);
DISPLAY 0.489362 (3600 2525);
PAINT SKYBLUE (3600 2525);
FORCEPROP 1 LAST PART_NUMBER CH622KMEB02
J 0
(3600 2325);
DISPLAY 0.489362 (3600 2325);
PAINT SKYBLUE (3600 2325);
FORCEPROP 1 LAST VOLTAGE 4V
J 0
(3600 2475);
DISPLAY 0.489362 (3600 2475);
PAINT SKYBLUE (3600 2475);
FORCEPROP 1 LAST PACK_TYPE C0402
J 0
(3600 2275);
DISPLAY 0.489362 (3600 2275);
PAINT SKYBLUE (3600 2275);
FORCEPROP 2 LAST CDS_LIB pure_quanta
J 0
(3550 2475);
PAINT MONO (3550 2475);
DISPLAY INVISIBLE (3550 2475);
FORCEPROP 1 LAST PATH I43
J 0
(3600 2625);
DISPLAY 0.978723 (3600 2625);
PAINT WHITE (3600 2625);
DISPLAY INVISIBLE (3600 2625);
FORCEADD Q_CAP..1
(4000 2475);
FORCEPROP 1 LAST LOCATION C2468
J 0
(4050 2575);
DISPLAY 0.489362 (4050 2575);
PAINT SKYBLUE (4050 2575);
FORCEPROP 2 LAST $SEC 1
J 0
(4050 2675);
DISPLAY 0.680851 (4050 2675);
PAINT MONO (4050 2675);
DISPLAY INVISIBLE (4050 2675);
FORCEPROP 2 LAST CDS_SEC 1
J 0
(4050 2675);
DISPLAY 1.021277 (4050 2675);
DISPLAY INVISIBLE (4050 2675);
FORCEPROP 1 LASTPIN (4000 2575) $PN 1
J 0
(4010 2555);
DISPLAY 0.489362 (4010 2555);
FORCEPROP 1 LASTPIN (4000 2375) $PN 2
J 0
(4010 2355);
DISPLAY 0.489362 (4010 2355);
FORCEPROP 1 LAST MATERIAL X6S
J 0
(4050 2375);
DISPLAY 0.489362 (4050 2375);
PAINT SKYBLUE (4050 2375);
FORCEPROP 1 LAST TOLERANCE 20%
J 0
(4050 2425);
DISPLAY 0.489362 (4050 2425);
PAINT SKYBLUE (4050 2425);
FORCEPROP 1 LAST VALUE 22UF
J 0
(4050 2525);
DISPLAY 0.489362 (4050 2525);
PAINT SKYBLUE (4050 2525);
FORCEPROP 1 LAST PART_NUMBER CH622KMEB02
J 0
(4050 2325);
DISPLAY 0.489362 (4050 2325);
PAINT SKYBLUE (4050 2325);
FORCEPROP 1 LAST VOLTAGE 4V
J 0
(4050 2475);
DISPLAY 0.489362 (4050 2475);
PAINT SKYBLUE (4050 2475);
FORCEPROP 1 LAST PACK_TYPE C0402
J 0
(4050 2275);
DISPLAY 0.489362 (4050 2275);
PAINT SKYBLUE (4050 2275);
FORCEPROP 2 LAST CDS_LIB pure_quanta
J 0
(4000 2475);
PAINT MONO (4000 2475);
DISPLAY INVISIBLE (4000 2475);
FORCEPROP 1 LAST PATH I44
J 0
(4050 2625);
DISPLAY 0.978723 (4050 2625);
PAINT WHITE (4050 2625);
DISPLAY INVISIBLE (4050 2625);
FORCEADD Q_CAP..1
(3550 3150);
FORCEPROP 1 LAST LOCATION C2460
J 0
(3600 3250);
DISPLAY 0.489362 (3600 3250);
PAINT SKYBLUE (3600 3250);
FORCEPROP 2 LAST $SEC 1
J 0
(3600 3350);
DISPLAY 0.680851 (3600 3350);
PAINT MONO (3600 3350);
DISPLAY INVISIBLE (3600 3350);
FORCEPROP 2 LAST CDS_SEC 1
J 0
(3600 3350);
DISPLAY 1.021277 (3600 3350);
DISPLAY INVISIBLE (3600 3350);
FORCEPROP 1 LASTPIN (3550 3250) $PN 1
J 0
(3560 3230);
DISPLAY 0.489362 (3560 3230);
FORCEPROP 1 LASTPIN (3550 3050) $PN 2
J 0
(3560 3030);
DISPLAY 0.489362 (3560 3030);
FORCEPROP 1 LAST MATERIAL X6S
J 0
(3600 3050);
DISPLAY 0.489362 (3600 3050);
PAINT SKYBLUE (3600 3050);
FORCEPROP 1 LAST TOLERANCE 20%
J 0
(3600 3100);
DISPLAY 0.489362 (3600 3100);
PAINT SKYBLUE (3600 3100);
FORCEPROP 1 LAST VALUE 22UF
J 0
(3600 3200);
DISPLAY 0.489362 (3600 3200);
PAINT SKYBLUE (3600 3200);
FORCEPROP 1 LAST PART_NUMBER CH622KMEB02
J 0
(3600 3000);
DISPLAY 0.489362 (3600 3000);
PAINT SKYBLUE (3600 3000);
FORCEPROP 1 LAST VOLTAGE 4V
J 0
(3600 3150);
DISPLAY 0.489362 (3600 3150);
PAINT SKYBLUE (3600 3150);
FORCEPROP 1 LAST PACK_TYPE C0402
J 0
(3600 2950);
DISPLAY 0.489362 (3600 2950);
PAINT SKYBLUE (3600 2950);
FORCEPROP 2 LAST CDS_LIB pure_quanta
J 0
(3550 3150);
PAINT MONO (3550 3150);
DISPLAY INVISIBLE (3550 3150);
FORCEPROP 1 LAST PATH I45
J 0
(3600 3300);
DISPLAY 0.978723 (3600 3300);
PAINT WHITE (3600 3300);
DISPLAY INVISIBLE (3600 3300);
FORCEADD Q_CAP..1
(3550 3850);
FORCEPROP 1 LAST LOCATION C2459
J 0
(3600 3950);
DISPLAY 0.489362 (3600 3950);
PAINT SKYBLUE (3600 3950);
FORCEPROP 2 LAST $SEC 1
J 0
(3600 4050);
DISPLAY 0.680851 (3600 4050);
PAINT MONO (3600 4050);
DISPLAY INVISIBLE (3600 4050);
FORCEPROP 2 LAST CDS_SEC 1
J 0
(3600 4050);
DISPLAY 1.021277 (3600 4050);
DISPLAY INVISIBLE (3600 4050);
FORCEPROP 1 LASTPIN (3550 3950) $PN 1
J 0
(3560 3930);
DISPLAY 0.489362 (3560 3930);
FORCEPROP 1 LASTPIN (3550 3750) $PN 2
J 0
(3560 3730);
DISPLAY 0.489362 (3560 3730);
FORCEPROP 1 LAST MATERIAL X6S
J 0
(3600 3750);
DISPLAY 0.489362 (3600 3750);
PAINT SKYBLUE (3600 3750);
FORCEPROP 1 LAST TOLERANCE 20%
J 0
(3600 3800);
DISPLAY 0.489362 (3600 3800);
PAINT SKYBLUE (3600 3800);
FORCEPROP 1 LAST VALUE 22UF
J 0
(3600 3900);
DISPLAY 0.489362 (3600 3900);
PAINT SKYBLUE (3600 3900);
FORCEPROP 1 LAST PART_NUMBER CH622KMEB02
J 0
(3600 3700);
DISPLAY 0.489362 (3600 3700);
PAINT SKYBLUE (3600 3700);
FORCEPROP 1 LAST VOLTAGE 4V
J 0
(3600 3850);
DISPLAY 0.489362 (3600 3850);
PAINT SKYBLUE (3600 3850);
FORCEPROP 1 LAST PACK_TYPE C0402
J 0
(3600 3650);
DISPLAY 0.489362 (3600 3650);
PAINT SKYBLUE (3600 3650);
FORCEPROP 2 LAST CDS_LIB pure_quanta
J 0
(3550 3850);
PAINT MONO (3550 3850);
DISPLAY INVISIBLE (3550 3850);
FORCEPROP 1 LAST PATH I46
J 0
(3600 4000);
DISPLAY 0.978723 (3600 4000);
PAINT WHITE (3600 4000);
DISPLAY INVISIBLE (3600 4000);
FORCEADD Q_CAP..1
(4000 3150);
FORCEPROP 1 LAST LOCATION C2467
J 0
(4050 3250);
DISPLAY 0.489362 (4050 3250);
PAINT SKYBLUE (4050 3250);
FORCEPROP 2 LAST $SEC 1
J 0
(4050 3350);
DISPLAY 0.680851 (4050 3350);
PAINT MONO (4050 3350);
DISPLAY INVISIBLE (4050 3350);
FORCEPROP 2 LAST CDS_SEC 1
J 0
(4050 3350);
DISPLAY 1.021277 (4050 3350);
DISPLAY INVISIBLE (4050 3350);
FORCEPROP 1 LASTPIN (4000 3250) $PN 1
J 0
(4010 3230);
DISPLAY 0.489362 (4010 3230);
FORCEPROP 1 LASTPIN (4000 3050) $PN 2
J 0
(4010 3030);
DISPLAY 0.489362 (4010 3030);
FORCEPROP 1 LAST MATERIAL X6S
J 0
(4050 3050);
DISPLAY 0.489362 (4050 3050);
PAINT SKYBLUE (4050 3050);
FORCEPROP 1 LAST TOLERANCE 20%
J 0
(4050 3100);
DISPLAY 0.489362 (4050 3100);
PAINT SKYBLUE (4050 3100);
FORCEPROP 1 LAST VALUE 22UF
J 0
(4050 3200);
DISPLAY 0.489362 (4050 3200);
PAINT SKYBLUE (4050 3200);
FORCEPROP 1 LAST PART_NUMBER CH622KMEB02
J 0
(4050 3000);
DISPLAY 0.489362 (4050 3000);
PAINT SKYBLUE (4050 3000);
FORCEPROP 1 LAST VOLTAGE 4V
J 0
(4050 3150);
DISPLAY 0.489362 (4050 3150);
PAINT SKYBLUE (4050 3150);
FORCEPROP 1 LAST PACK_TYPE C0402
J 0
(4050 2950);
DISPLAY 0.489362 (4050 2950);
PAINT SKYBLUE (4050 2950);
FORCEPROP 2 LAST CDS_LIB pure_quanta
J 0
(4000 3150);
PAINT MONO (4000 3150);
DISPLAY INVISIBLE (4000 3150);
FORCEPROP 1 LAST PATH I47
J 0
(4050 3300);
DISPLAY 0.978723 (4050 3300);
PAINT WHITE (4050 3300);
DISPLAY INVISIBLE (4050 3300);
FORCEADD Q_CAP..1
(4000 3850);
FORCEPROP 1 LAST LOCATION C2466
J 0
(4050 3950);
DISPLAY 0.489362 (4050 3950);
PAINT SKYBLUE (4050 3950);
FORCEPROP 2 LAST $SEC 1
J 0
(4050 4050);
DISPLAY 0.680851 (4050 4050);
PAINT MONO (4050 4050);
DISPLAY INVISIBLE (4050 4050);
FORCEPROP 2 LAST CDS_SEC 1
J 0
(4050 4050);
DISPLAY 1.021277 (4050 4050);
DISPLAY INVISIBLE (4050 4050);
FORCEPROP 1 LASTPIN (4000 3950) $PN 1
J 0
(4010 3930);
DISPLAY 0.489362 (4010 3930);
FORCEPROP 1 LASTPIN (4000 3750) $PN 2
J 0
(4010 3730);
DISPLAY 0.489362 (4010 3730);
FORCEPROP 1 LAST MATERIAL X6S
J 0
(4050 3750);
DISPLAY 0.489362 (4050 3750);
PAINT SKYBLUE (4050 3750);
FORCEPROP 1 LAST TOLERANCE 20%
J 0
(4050 3800);
DISPLAY 0.489362 (4050 3800);
PAINT SKYBLUE (4050 3800);
FORCEPROP 1 LAST VALUE 22UF
J 0
(4050 3900);
DISPLAY 0.489362 (4050 3900);
PAINT SKYBLUE (4050 3900);
FORCEPROP 1 LAST PART_NUMBER CH622KMEB02
J 0
(4050 3700);
DISPLAY 0.489362 (4050 3700);
PAINT SKYBLUE (4050 3700);
FORCEPROP 1 LAST VOLTAGE 4V
J 0
(4050 3850);
DISPLAY 0.489362 (4050 3850);
PAINT SKYBLUE (4050 3850);
FORCEPROP 1 LAST PACK_TYPE C0402
J 0
(4050 3650);
DISPLAY 0.489362 (4050 3650);
PAINT SKYBLUE (4050 3650);
FORCEPROP 2 LAST CDS_LIB pure_quanta
J 0
(4000 3850);
PAINT MONO (4000 3850);
DISPLAY INVISIBLE (4000 3850);
FORCEPROP 1 LAST PATH I48
J 0
(4050 4000);
DISPLAY 0.978723 (4050 4000);
PAINT WHITE (4050 4000);
DISPLAY INVISIBLE (4050 4000);
FORCEADD UNIVERSAL_POWER..1
(400 4125);
FORCEPROP 3 LASTPIN (400 4075) SIG_NAME PVDDCR_SOC_P1\g
J 0
(410 4085);
DISPLAY 0.659574 (410 4085);
PAINT MONO (410 4085);
DISPLAY INVISIBLE (410 4085);
FORCEPROP 1 LAST HDL_POWER PVDDCR_SOC_P1
J 1
(400 4175);
DISPLAY 0.489362 (400 4175);
PAINT GREEN (400 4175);
FORCEPROP 2 LAST CDS_LIB pure_quanta_power
J 0
(400 4125);
DISPLAY INVISIBLE (400 4125);
FORCEPROP 1 LAST PATH I49
J 0
(450 4150);
DISPLAY 0.872340 (450 4150);
PAINT AQUA (450 4150);
DISPLAY INVISIBLE (450 4150);
FORCEADD Q_CAP..1
(850 1800);
FORCEPROP 1 LAST LOCATION C2420
J 0
(900 1900);
DISPLAY 0.489362 (900 1900);
PAINT SKYBLUE (900 1900);
FORCEPROP 2 LAST $SEC 1
J 0
(900 2000);
DISPLAY 0.680851 (900 2000);
PAINT MONO (900 2000);
DISPLAY INVISIBLE (900 2000);
FORCEPROP 2 LAST CDS_SEC 1
J 0
(900 2000);
DISPLAY 1.021277 (900 2000);
DISPLAY INVISIBLE (900 2000);
FORCEPROP 1 LASTPIN (850 1900) $PN 1
J 0
(860 1880);
DISPLAY 0.489362 (860 1880);
FORCEPROP 1 LASTPIN (850 1700) $PN 2
J 0
(860 1680);
DISPLAY 0.489362 (860 1680);
FORCEPROP 1 LAST MATERIAL X6S
J 0
(900 1700);
DISPLAY 0.489362 (900 1700);
PAINT SKYBLUE (900 1700);
FORCEPROP 1 LAST TOLERANCE 20%
J 0
(900 1750);
DISPLAY 0.489362 (900 1750);
PAINT SKYBLUE (900 1750);
FORCEPROP 1 LAST VALUE 22UF
J 0
(900 1850);
DISPLAY 0.489362 (900 1850);
PAINT SKYBLUE (900 1850);
FORCEPROP 1 LAST PART_NUMBER CH622KMEB02
J 0
(900 1650);
DISPLAY 0.489362 (900 1650);
PAINT SKYBLUE (900 1650);
FORCEPROP 1 LAST VOLTAGE 4V
J 0
(900 1800);
DISPLAY 0.489362 (900 1800);
PAINT SKYBLUE (900 1800);
FORCEPROP 1 LAST PACK_TYPE C0402
J 0
(900 1600);
DISPLAY 0.489362 (900 1600);
PAINT SKYBLUE (900 1600);
FORCEPROP 2 LAST CDS_LIB pure_quanta
J 0
(850 1800);
PAINT MONO (850 1800);
DISPLAY INVISIBLE (850 1800);
FORCEPROP 1 LAST PATH I5
J 0
(900 1950);
DISPLAY 0.978723 (900 1950);
PAINT WHITE (900 1950);
DISPLAY INVISIBLE (900 1950);
FORCEADD Q_CAP..1
(400 4550);
FORCEPROP 1 LAST LOCATION C2409
J 0
(450 4650);
DISPLAY 0.489362 (450 4650);
PAINT SKYBLUE (450 4650);
FORCEPROP 2 LAST $SEC 1
J 0
(450 4750);
DISPLAY 0.680851 (450 4750);
PAINT MONO (450 4750);
DISPLAY INVISIBLE (450 4750);
FORCEPROP 2 LAST CDS_SEC 1
J 0
(450 4750);
DISPLAY 1.021277 (450 4750);
DISPLAY INVISIBLE (450 4750);
FORCEPROP 1 LASTPIN (400 4650) $PN 1
J 0
(410 4630);
DISPLAY 0.489362 (410 4630);
FORCEPROP 1 LASTPIN (400 4450) $PN 2
J 0
(410 4430);
DISPLAY 0.489362 (410 4430);
FORCEPROP 1 LAST MATERIAL X6S
J 0
(450 4450);
DISPLAY 0.489362 (450 4450);
PAINT SKYBLUE (450 4450);
FORCEPROP 1 LAST TOLERANCE 20%
J 0
(450 4500);
DISPLAY 0.489362 (450 4500);
PAINT SKYBLUE (450 4500);
FORCEPROP 1 LAST VALUE 22UF
J 0
(450 4600);
DISPLAY 0.489362 (450 4600);
PAINT SKYBLUE (450 4600);
FORCEPROP 1 LAST PART_NUMBER CH622KMEB02
J 0
(450 4400);
DISPLAY 0.489362 (450 4400);
PAINT SKYBLUE (450 4400);
FORCEPROP 1 LAST VOLTAGE 4V
J 0
(450 4550);
DISPLAY 0.489362 (450 4550);
PAINT SKYBLUE (450 4550);
FORCEPROP 1 LAST PACK_TYPE C0402
J 0
(450 4350);
DISPLAY 0.489362 (450 4350);
PAINT SKYBLUE (450 4350);
FORCEPROP 2 LAST CDS_LIB pure_quanta
J 0
(400 4550);
PAINT MONO (400 4550);
DISPLAY INVISIBLE (400 4550);
FORCEPROP 1 LAST PATH I50
J 0
(450 4700);
DISPLAY 0.978723 (450 4700);
PAINT WHITE (450 4700);
DISPLAY INVISIBLE (450 4700);
FORCEADD UNIVERSAL_POWER..1
(400 4825);
FORCEPROP 3 LASTPIN (400 4775) SIG_NAME PVDDCR_SOC_P1\g
J 0
(410 4785);
DISPLAY 0.659574 (410 4785);
PAINT MONO (410 4785);
DISPLAY INVISIBLE (410 4785);
FORCEPROP 1 LAST HDL_POWER PVDDCR_SOC_P1
J 1
(400 4900);
DISPLAY 0.489362 (400 4900);
PAINT GREEN (400 4900);
FORCEPROP 2 LAST CDS_LIB pure_quanta_power
J 0
(400 4825);
DISPLAY INVISIBLE (400 4825);
FORCEPROP 1 LAST PATH I51
J 0
(450 4850);
DISPLAY 0.872340 (450 4850);
PAINT AQUA (450 4850);
DISPLAY INVISIBLE (450 4850);
FORCEADD Q_CAP..1
(850 4550);
FORCEPROP 1 LAST LOCATION C2416
J 0
(900 4650);
DISPLAY 0.489362 (900 4650);
PAINT SKYBLUE (900 4650);
FORCEPROP 2 LAST $SEC 1
J 0
(900 4750);
DISPLAY 0.680851 (900 4750);
PAINT MONO (900 4750);
DISPLAY INVISIBLE (900 4750);
FORCEPROP 2 LAST CDS_SEC 1
J 0
(900 4750);
DISPLAY 1.021277 (900 4750);
DISPLAY INVISIBLE (900 4750);
FORCEPROP 1 LASTPIN (850 4650) $PN 1
J 0
(860 4630);
DISPLAY 0.489362 (860 4630);
FORCEPROP 1 LASTPIN (850 4450) $PN 2
J 0
(860 4430);
DISPLAY 0.489362 (860 4430);
FORCEPROP 1 LAST MATERIAL X6S
J 0
(900 4450);
DISPLAY 0.489362 (900 4450);
PAINT SKYBLUE (900 4450);
FORCEPROP 1 LAST TOLERANCE 20%
J 0
(900 4500);
DISPLAY 0.489362 (900 4500);
PAINT SKYBLUE (900 4500);
FORCEPROP 1 LAST VALUE 22UF
J 0
(900 4600);
DISPLAY 0.489362 (900 4600);
PAINT SKYBLUE (900 4600);
FORCEPROP 1 LAST PART_NUMBER CH622KMEB02
J 0
(900 4400);
DISPLAY 0.489362 (900 4400);
PAINT SKYBLUE (900 4400);
FORCEPROP 1 LAST VOLTAGE 4V
J 0
(900 4550);
DISPLAY 0.489362 (900 4550);
PAINT SKYBLUE (900 4550);
FORCEPROP 1 LAST PACK_TYPE C0402
J 0
(900 4350);
DISPLAY 0.489362 (900 4350);
PAINT SKYBLUE (900 4350);
FORCEPROP 2 LAST CDS_LIB pure_quanta
J 0
(850 4550);
PAINT MONO (850 4550);
DISPLAY INVISIBLE (850 4550);
FORCEPROP 1 LAST PATH I52
J 0
(900 4700);
DISPLAY 0.978723 (900 4700);
PAINT WHITE (900 4700);
DISPLAY INVISIBLE (900 4700);
FORCEADD Q_CAP..1
(400 5225);
FORCEPROP 1 LAST LOCATION C2408
J 0
(450 5325);
DISPLAY 0.489362 (450 5325);
PAINT SKYBLUE (450 5325);
FORCEPROP 2 LAST $SEC 1
J 0
(450 5425);
DISPLAY 0.680851 (450 5425);
PAINT MONO (450 5425);
DISPLAY INVISIBLE (450 5425);
FORCEPROP 2 LAST CDS_SEC 1
J 0
(450 5425);
DISPLAY 1.021277 (450 5425);
DISPLAY INVISIBLE (450 5425);
FORCEPROP 1 LASTPIN (400 5325) $PN 1
J 0
(410 5305);
DISPLAY 0.489362 (410 5305);
FORCEPROP 1 LASTPIN (400 5125) $PN 2
J 0
(410 5105);
DISPLAY 0.489362 (410 5105);
FORCEPROP 1 LAST MATERIAL X6S
J 0
(450 5125);
DISPLAY 0.489362 (450 5125);
PAINT SKYBLUE (450 5125);
FORCEPROP 1 LAST TOLERANCE 20%
J 0
(450 5175);
DISPLAY 0.489362 (450 5175);
PAINT SKYBLUE (450 5175);
FORCEPROP 1 LAST VALUE 22UF
J 0
(450 5275);
DISPLAY 0.489362 (450 5275);
PAINT SKYBLUE (450 5275);
FORCEPROP 1 LAST PART_NUMBER CH622KMEB02
J 0
(450 5075);
DISPLAY 0.489362 (450 5075);
PAINT SKYBLUE (450 5075);
FORCEPROP 1 LAST VOLTAGE 4V
J 0
(450 5225);
DISPLAY 0.489362 (450 5225);
PAINT SKYBLUE (450 5225);
FORCEPROP 1 LAST PACK_TYPE C0402
J 0
(450 5025);
DISPLAY 0.489362 (450 5025);
PAINT SKYBLUE (450 5025);
FORCEPROP 2 LAST CDS_LIB pure_quanta
J 0
(400 5225);
PAINT MONO (400 5225);
DISPLAY INVISIBLE (400 5225);
FORCEPROP 1 LAST PATH I53
J 0
(450 5375);
DISPLAY 0.978723 (450 5375);
PAINT WHITE (450 5375);
DISPLAY INVISIBLE (450 5375);
FORCEADD UNIVERSAL_POWER..1
(400 5500);
FORCEPROP 3 LASTPIN (400 5450) SIG_NAME PVDDCR_SOC_P1\g
J 0
(410 5460);
DISPLAY 0.659574 (410 5460);
PAINT MONO (410 5460);
DISPLAY INVISIBLE (410 5460);
FORCEPROP 1 LAST HDL_POWER PVDDCR_SOC_P1
J 1
(400 5550);
DISPLAY 0.489362 (400 5550);
PAINT GREEN (400 5550);
FORCEPROP 2 LAST CDS_LIB pure_quanta_power
J 0
(400 5500);
DISPLAY INVISIBLE (400 5500);
FORCEPROP 1 LAST PATH I54
J 0
(450 5525);
DISPLAY 0.872340 (450 5525);
PAINT AQUA (450 5525);
DISPLAY INVISIBLE (450 5525);
FORCEADD Q_CAP..1
(400 5875);
FORCEPROP 1 LAST LOCATION C2407
J 0
(450 5975);
DISPLAY 0.489362 (450 5975);
PAINT SKYBLUE (450 5975);
FORCEPROP 2 LAST $SEC 1
J 0
(450 6075);
DISPLAY 0.680851 (450 6075);
PAINT MONO (450 6075);
DISPLAY INVISIBLE (450 6075);
FORCEPROP 2 LAST CDS_SEC 1
J 0
(450 6075);
DISPLAY 1.021277 (450 6075);
DISPLAY INVISIBLE (450 6075);
FORCEPROP 1 LASTPIN (400 5975) $PN 1
J 0
(410 5955);
DISPLAY 0.489362 (410 5955);
FORCEPROP 1 LASTPIN (400 5775) $PN 2
J 0
(410 5755);
DISPLAY 0.489362 (410 5755);
FORCEPROP 1 LAST MATERIAL X6S
J 0
(450 5775);
DISPLAY 0.489362 (450 5775);
PAINT SKYBLUE (450 5775);
FORCEPROP 1 LAST TOLERANCE 20%
J 0
(450 5825);
DISPLAY 0.489362 (450 5825);
PAINT SKYBLUE (450 5825);
FORCEPROP 1 LAST VALUE 22UF
J 0
(450 5925);
DISPLAY 0.489362 (450 5925);
PAINT SKYBLUE (450 5925);
FORCEPROP 1 LAST PART_NUMBER CH622KMEB02
J 0
(450 5725);
DISPLAY 0.489362 (450 5725);
PAINT SKYBLUE (450 5725);
FORCEPROP 1 LAST VOLTAGE 4V
J 0
(450 5875);
DISPLAY 0.489362 (450 5875);
PAINT SKYBLUE (450 5875);
FORCEPROP 1 LAST PACK_TYPE C0402
J 0
(450 5675);
DISPLAY 0.489362 (450 5675);
PAINT SKYBLUE (450 5675);
FORCEPROP 2 LAST CDS_LIB pure_quanta
J 0
(400 5875);
PAINT MONO (400 5875);
DISPLAY INVISIBLE (400 5875);
FORCEPROP 1 LAST PATH I55
J 0
(450 6025);
DISPLAY 0.978723 (450 6025);
PAINT WHITE (450 6025);
DISPLAY INVISIBLE (450 6025);
FORCEADD Q_CAP..1
(850 5225);
FORCEPROP 1 LAST LOCATION C2415
J 0
(900 5325);
DISPLAY 0.489362 (900 5325);
PAINT SKYBLUE (900 5325);
FORCEPROP 2 LAST $SEC 1
J 0
(900 5425);
DISPLAY 0.680851 (900 5425);
PAINT MONO (900 5425);
DISPLAY INVISIBLE (900 5425);
FORCEPROP 2 LAST CDS_SEC 1
J 0
(900 5425);
DISPLAY 1.021277 (900 5425);
DISPLAY INVISIBLE (900 5425);
FORCEPROP 1 LASTPIN (850 5325) $PN 1
J 0
(860 5305);
DISPLAY 0.489362 (860 5305);
FORCEPROP 1 LASTPIN (850 5125) $PN 2
J 0
(860 5105);
DISPLAY 0.489362 (860 5105);
FORCEPROP 1 LAST MATERIAL X6S
J 0
(900 5125);
DISPLAY 0.489362 (900 5125);
PAINT SKYBLUE (900 5125);
FORCEPROP 1 LAST TOLERANCE 20%
J 0
(900 5175);
DISPLAY 0.489362 (900 5175);
PAINT SKYBLUE (900 5175);
FORCEPROP 1 LAST VALUE 22UF
J 0
(900 5275);
DISPLAY 0.489362 (900 5275);
PAINT SKYBLUE (900 5275);
FORCEPROP 1 LAST PART_NUMBER CH622KMEB02
J 0
(900 5075);
DISPLAY 0.489362 (900 5075);
PAINT SKYBLUE (900 5075);
FORCEPROP 1 LAST VOLTAGE 4V
J 0
(900 5225);
DISPLAY 0.489362 (900 5225);
PAINT SKYBLUE (900 5225);
FORCEPROP 1 LAST PACK_TYPE C0402
J 0
(900 5025);
DISPLAY 0.489362 (900 5025);
PAINT SKYBLUE (900 5025);
FORCEPROP 2 LAST CDS_LIB pure_quanta
J 0
(850 5225);
PAINT MONO (850 5225);
DISPLAY INVISIBLE (850 5225);
FORCEPROP 1 LAST PATH I56
J 0
(900 5375);
DISPLAY 0.978723 (900 5375);
PAINT WHITE (900 5375);
DISPLAY INVISIBLE (900 5375);
FORCEADD Q_CAP..1
(850 5875);
FORCEPROP 1 LAST LOCATION C2414
J 0
(900 5975);
DISPLAY 0.489362 (900 5975);
PAINT SKYBLUE (900 5975);
FORCEPROP 2 LAST $SEC 1
J 0
(900 6075);
DISPLAY 0.680851 (900 6075);
PAINT MONO (900 6075);
DISPLAY INVISIBLE (900 6075);
FORCEPROP 2 LAST CDS_SEC 1
J 0
(900 6075);
DISPLAY 1.021277 (900 6075);
DISPLAY INVISIBLE (900 6075);
FORCEPROP 1 LASTPIN (850 5975) $PN 1
J 0
(860 5955);
DISPLAY 0.489362 (860 5955);
FORCEPROP 1 LASTPIN (850 5775) $PN 2
J 0
(860 5755);
DISPLAY 0.489362 (860 5755);
FORCEPROP 1 LAST MATERIAL X6S
J 0
(900 5775);
DISPLAY 0.489362 (900 5775);
PAINT SKYBLUE (900 5775);
FORCEPROP 1 LAST TOLERANCE 20%
J 0
(900 5825);
DISPLAY 0.489362 (900 5825);
PAINT SKYBLUE (900 5825);
FORCEPROP 1 LAST VALUE 22UF
J 0
(900 5925);
DISPLAY 0.489362 (900 5925);
PAINT SKYBLUE (900 5925);
FORCEPROP 1 LAST PART_NUMBER CH622KMEB02
J 0
(900 5725);
DISPLAY 0.489362 (900 5725);
PAINT SKYBLUE (900 5725);
FORCEPROP 1 LAST VOLTAGE 4V
J 0
(900 5875);
DISPLAY 0.489362 (900 5875);
PAINT SKYBLUE (900 5875);
FORCEPROP 1 LAST PACK_TYPE C0402
J 0
(900 5675);
DISPLAY 0.489362 (900 5675);
PAINT SKYBLUE (900 5675);
FORCEPROP 2 LAST CDS_LIB pure_quanta
J 0
(850 5875);
PAINT MONO (850 5875);
DISPLAY INVISIBLE (850 5875);
FORCEPROP 1 LAST PATH I57
J 0
(900 6025);
DISPLAY 0.978723 (900 6025);
PAINT WHITE (900 6025);
DISPLAY INVISIBLE (900 6025);
FORCEADD Q_CAP..1
(1300 4550);
FORCEPROP 1 LAST LOCATION C2423
J 0
(1350 4650);
DISPLAY 0.489362 (1350 4650);
PAINT SKYBLUE (1350 4650);
FORCEPROP 2 LAST $SEC 1
J 0
(1350 4750);
DISPLAY 0.680851 (1350 4750);
PAINT MONO (1350 4750);
DISPLAY INVISIBLE (1350 4750);
FORCEPROP 2 LAST CDS_SEC 1
J 0
(1350 4750);
DISPLAY 1.021277 (1350 4750);
DISPLAY INVISIBLE (1350 4750);
FORCEPROP 1 LASTPIN (1300 4650) $PN 1
J 0
(1310 4630);
DISPLAY 0.489362 (1310 4630);
FORCEPROP 1 LASTPIN (1300 4450) $PN 2
J 0
(1310 4430);
DISPLAY 0.489362 (1310 4430);
FORCEPROP 1 LAST MATERIAL X6S
J 0
(1350 4450);
DISPLAY 0.489362 (1350 4450);
PAINT SKYBLUE (1350 4450);
FORCEPROP 1 LAST TOLERANCE 20%
J 0
(1350 4500);
DISPLAY 0.489362 (1350 4500);
PAINT SKYBLUE (1350 4500);
FORCEPROP 1 LAST VALUE 22UF
J 0
(1350 4600);
DISPLAY 0.489362 (1350 4600);
PAINT SKYBLUE (1350 4600);
FORCEPROP 1 LAST PART_NUMBER CH622KMEB02
J 0
(1350 4400);
DISPLAY 0.489362 (1350 4400);
PAINT SKYBLUE (1350 4400);
FORCEPROP 1 LAST VOLTAGE 4V
J 0
(1350 4550);
DISPLAY 0.489362 (1350 4550);
PAINT SKYBLUE (1350 4550);
FORCEPROP 1 LAST PACK_TYPE C0402
J 0
(1350 4350);
DISPLAY 0.489362 (1350 4350);
PAINT SKYBLUE (1350 4350);
FORCEPROP 2 LAST CDS_LIB pure_quanta
J 0
(1300 4550);
PAINT MONO (1300 4550);
DISPLAY INVISIBLE (1300 4550);
FORCEPROP 1 LAST PATH I58
J 0
(1350 4700);
DISPLAY 0.978723 (1350 4700);
PAINT WHITE (1350 4700);
DISPLAY INVISIBLE (1350 4700);
FORCEADD Q_CAP..1
(1750 4550);
FORCEPROP 1 LAST LOCATION C2430
J 0
(1800 4650);
DISPLAY 0.489362 (1800 4650);
PAINT SKYBLUE (1800 4650);
FORCEPROP 2 LAST $SEC 1
J 0
(1800 4750);
DISPLAY 0.680851 (1800 4750);
PAINT MONO (1800 4750);
DISPLAY INVISIBLE (1800 4750);
FORCEPROP 2 LAST CDS_SEC 1
J 0
(1800 4750);
DISPLAY 1.021277 (1800 4750);
DISPLAY INVISIBLE (1800 4750);
FORCEPROP 1 LASTPIN (1750 4650) $PN 1
J 0
(1760 4630);
DISPLAY 0.489362 (1760 4630);
FORCEPROP 1 LASTPIN (1750 4450) $PN 2
J 0
(1760 4430);
DISPLAY 0.489362 (1760 4430);
FORCEPROP 1 LAST MATERIAL X6S
J 0
(1800 4450);
DISPLAY 0.489362 (1800 4450);
PAINT SKYBLUE (1800 4450);
FORCEPROP 1 LAST TOLERANCE 20%
J 0
(1800 4500);
DISPLAY 0.489362 (1800 4500);
PAINT SKYBLUE (1800 4500);
FORCEPROP 1 LAST VALUE 22UF
J 0
(1800 4600);
DISPLAY 0.489362 (1800 4600);
PAINT SKYBLUE (1800 4600);
FORCEPROP 1 LAST PART_NUMBER CH622KMEB02
J 0
(1800 4400);
DISPLAY 0.489362 (1800 4400);
PAINT SKYBLUE (1800 4400);
FORCEPROP 1 LAST VOLTAGE 4V
J 0
(1800 4550);
DISPLAY 0.489362 (1800 4550);
PAINT SKYBLUE (1800 4550);
FORCEPROP 1 LAST PACK_TYPE C0402
J 0
(1800 4350);
DISPLAY 0.489362 (1800 4350);
PAINT SKYBLUE (1800 4350);
FORCEPROP 2 LAST CDS_LIB pure_quanta
J 0
(1750 4550);
PAINT MONO (1750 4550);
DISPLAY INVISIBLE (1750 4550);
FORCEPROP 1 LAST PATH I59
J 0
(1800 4700);
DISPLAY 0.978723 (1800 4700);
PAINT WHITE (1800 4700);
DISPLAY INVISIBLE (1800 4700);
FORCEADD Q_CAP..1
(1300 1075);
FORCEPROP 1 LAST LOCATION C3914
J 0
(1350 1175);
DISPLAY 0.489362 (1350 1175);
PAINT SKYBLUE (1350 1175);
FORCEPROP 2 LAST $SEC 1
J 0
(1350 1275);
DISPLAY 0.680851 (1350 1275);
PAINT MONO (1350 1275);
DISPLAY INVISIBLE (1350 1275);
FORCEPROP 2 LAST CDS_SEC 1
J 0
(1350 1275);
DISPLAY 1.021277 (1350 1275);
DISPLAY INVISIBLE (1350 1275);
FORCEPROP 1 LASTPIN (1300 1175) $PN 1
J 0
(1310 1155);
DISPLAY 0.489362 (1310 1155);
FORCEPROP 1 LASTPIN (1300 975) $PN 2
J 0
(1310 955);
DISPLAY 0.489362 (1310 955);
FORCEPROP 1 LAST MATERIAL X6S
J 0
(1350 975);
DISPLAY 0.489362 (1350 975);
PAINT SKYBLUE (1350 975);
FORCEPROP 1 LAST TOLERANCE 20%
J 0
(1350 1025);
DISPLAY 0.489362 (1350 1025);
PAINT SKYBLUE (1350 1025);
FORCEPROP 1 LAST VALUE 22UF
J 0
(1350 1125);
DISPLAY 0.489362 (1350 1125);
PAINT SKYBLUE (1350 1125);
FORCEPROP 1 LAST PART_NUMBER CH622KMEB02
J 0
(1350 925);
DISPLAY 0.489362 (1350 925);
PAINT SKYBLUE (1350 925);
FORCEPROP 1 LAST VOLTAGE 4V
J 0
(1350 1075);
DISPLAY 0.489362 (1350 1075);
PAINT SKYBLUE (1350 1075);
FORCEPROP 1 LAST PACK_TYPE C0402
J 0
(1350 875);
DISPLAY 0.489362 (1350 875);
PAINT SKYBLUE (1350 875);
FORCEPROP 2 LAST CDS_LIB pure_quanta
J 0
(1300 1075);
PAINT MONO (1300 1075);
DISPLAY INVISIBLE (1300 1075);
FORCEPROP 1 LAST PATH I6
J 0
(1350 1225);
DISPLAY 0.978723 (1350 1225);
PAINT WHITE (1350 1225);
DISPLAY INVISIBLE (1350 1225);
FORCEADD Q_CAP..1
(1300 5225);
FORCEPROP 1 LAST LOCATION C2422
J 0
(1350 5325);
DISPLAY 0.489362 (1350 5325);
PAINT SKYBLUE (1350 5325);
FORCEPROP 2 LAST $SEC 1
J 0
(1350 5425);
DISPLAY 0.680851 (1350 5425);
PAINT MONO (1350 5425);
DISPLAY INVISIBLE (1350 5425);
FORCEPROP 2 LAST CDS_SEC 1
J 0
(1350 5425);
DISPLAY 1.021277 (1350 5425);
DISPLAY INVISIBLE (1350 5425);
FORCEPROP 1 LASTPIN (1300 5325) $PN 1
J 0
(1310 5305);
DISPLAY 0.489362 (1310 5305);
FORCEPROP 1 LASTPIN (1300 5125) $PN 2
J 0
(1310 5105);
DISPLAY 0.489362 (1310 5105);
FORCEPROP 1 LAST MATERIAL X6S
J 0
(1350 5125);
DISPLAY 0.489362 (1350 5125);
PAINT SKYBLUE (1350 5125);
FORCEPROP 1 LAST TOLERANCE 20%
J 0
(1350 5175);
DISPLAY 0.489362 (1350 5175);
PAINT SKYBLUE (1350 5175);
FORCEPROP 1 LAST VALUE 22UF
J 0
(1350 5275);
DISPLAY 0.489362 (1350 5275);
PAINT SKYBLUE (1350 5275);
FORCEPROP 1 LAST PART_NUMBER CH622KMEB02
J 0
(1350 5075);
DISPLAY 0.489362 (1350 5075);
PAINT SKYBLUE (1350 5075);
FORCEPROP 1 LAST VOLTAGE 4V
J 0
(1350 5225);
DISPLAY 0.489362 (1350 5225);
PAINT SKYBLUE (1350 5225);
FORCEPROP 1 LAST PACK_TYPE C0402
J 0
(1350 5025);
DISPLAY 0.489362 (1350 5025);
PAINT SKYBLUE (1350 5025);
FORCEPROP 2 LAST CDS_LIB pure_quanta
J 0
(1300 5225);
PAINT MONO (1300 5225);
DISPLAY INVISIBLE (1300 5225);
FORCEPROP 1 LAST PATH I60
J 0
(1350 5375);
DISPLAY 0.978723 (1350 5375);
PAINT WHITE (1350 5375);
DISPLAY INVISIBLE (1350 5375);
FORCEADD Q_CAP..1
(1300 5875);
FORCEPROP 1 LAST LOCATION C2421
J 0
(1350 5975);
DISPLAY 0.489362 (1350 5975);
PAINT SKYBLUE (1350 5975);
FORCEPROP 2 LAST $SEC 1
J 0
(1350 6075);
DISPLAY 0.680851 (1350 6075);
PAINT MONO (1350 6075);
DISPLAY INVISIBLE (1350 6075);
FORCEPROP 2 LAST CDS_SEC 1
J 0
(1350 6075);
DISPLAY 1.021277 (1350 6075);
DISPLAY INVISIBLE (1350 6075);
FORCEPROP 1 LASTPIN (1300 5975) $PN 1
J 0
(1310 5955);
DISPLAY 0.489362 (1310 5955);
FORCEPROP 1 LASTPIN (1300 5775) $PN 2
J 0
(1310 5755);
DISPLAY 0.489362 (1310 5755);
FORCEPROP 1 LAST MATERIAL X6S
J 0
(1350 5775);
DISPLAY 0.489362 (1350 5775);
PAINT SKYBLUE (1350 5775);
FORCEPROP 1 LAST TOLERANCE 20%
J 0
(1350 5825);
DISPLAY 0.489362 (1350 5825);
PAINT SKYBLUE (1350 5825);
FORCEPROP 1 LAST VALUE 22UF
J 0
(1350 5925);
DISPLAY 0.489362 (1350 5925);
PAINT SKYBLUE (1350 5925);
FORCEPROP 1 LAST PART_NUMBER CH622KMEB02
J 0
(1350 5725);
DISPLAY 0.489362 (1350 5725);
PAINT SKYBLUE (1350 5725);
FORCEPROP 1 LAST VOLTAGE 4V
J 0
(1350 5875);
DISPLAY 0.489362 (1350 5875);
PAINT SKYBLUE (1350 5875);
FORCEPROP 1 LAST PACK_TYPE C0402
J 0
(1350 5675);
DISPLAY 0.489362 (1350 5675);
PAINT SKYBLUE (1350 5675);
FORCEPROP 2 LAST CDS_LIB pure_quanta
J 0
(1300 5875);
PAINT MONO (1300 5875);
DISPLAY INVISIBLE (1300 5875);
FORCEPROP 1 LAST PATH I61
J 0
(1350 6025);
DISPLAY 0.978723 (1350 6025);
PAINT WHITE (1350 6025);
DISPLAY INVISIBLE (1350 6025);
FORCEADD Q_CAP..1
(1750 5225);
FORCEPROP 1 LAST LOCATION C2429
J 0
(1800 5325);
DISPLAY 0.489362 (1800 5325);
PAINT SKYBLUE (1800 5325);
FORCEPROP 2 LAST $SEC 1
J 0
(1800 5425);
DISPLAY 0.680851 (1800 5425);
PAINT MONO (1800 5425);
DISPLAY INVISIBLE (1800 5425);
FORCEPROP 2 LAST CDS_SEC 1
J 0
(1800 5425);
DISPLAY 1.021277 (1800 5425);
DISPLAY INVISIBLE (1800 5425);
FORCEPROP 1 LASTPIN (1750 5325) $PN 1
J 0
(1760 5305);
DISPLAY 0.489362 (1760 5305);
FORCEPROP 1 LASTPIN (1750 5125) $PN 2
J 0
(1760 5105);
DISPLAY 0.489362 (1760 5105);
FORCEPROP 1 LAST MATERIAL X6S
J 0
(1800 5125);
DISPLAY 0.489362 (1800 5125);
PAINT SKYBLUE (1800 5125);
FORCEPROP 1 LAST TOLERANCE 20%
J 0
(1800 5175);
DISPLAY 0.489362 (1800 5175);
PAINT SKYBLUE (1800 5175);
FORCEPROP 1 LAST VALUE 22UF
J 0
(1800 5275);
DISPLAY 0.489362 (1800 5275);
PAINT SKYBLUE (1800 5275);
FORCEPROP 1 LAST PART_NUMBER CH622KMEB02
J 0
(1800 5075);
DISPLAY 0.489362 (1800 5075);
PAINT SKYBLUE (1800 5075);
FORCEPROP 1 LAST VOLTAGE 4V
J 0
(1800 5225);
DISPLAY 0.489362 (1800 5225);
PAINT SKYBLUE (1800 5225);
FORCEPROP 1 LAST PACK_TYPE C0402
J 0
(1800 5025);
DISPLAY 0.489362 (1800 5025);
PAINT SKYBLUE (1800 5025);
FORCEPROP 2 LAST CDS_LIB pure_quanta
J 0
(1750 5225);
PAINT MONO (1750 5225);
DISPLAY INVISIBLE (1750 5225);
FORCEPROP 1 LAST PATH I62
J 0
(1800 5375);
DISPLAY 0.978723 (1800 5375);
PAINT WHITE (1800 5375);
DISPLAY INVISIBLE (1800 5375);
FORCEADD UNIVERSAL_POWER..1
(400 6150);
FORCEPROP 3 LASTPIN (400 6100) SIG_NAME PVDDCR_SOC_P1\g
J 0
(410 6110);
DISPLAY 0.659574 (410 6110);
PAINT MONO (410 6110);
DISPLAY INVISIBLE (410 6110);
FORCEPROP 1 LAST HDL_POWER PVDDCR_SOC_P1
J 1
(400 6200);
DISPLAY 0.489362 (400 6200);
PAINT GREEN (400 6200);
FORCEPROP 2 LAST CDS_LIB pure_quanta_power
J 0
(400 6150);
DISPLAY INVISIBLE (400 6150);
FORCEPROP 1 LAST PATH I63
J 0
(450 6175);
DISPLAY 0.872340 (450 6175);
PAINT AQUA (450 6175);
DISPLAY INVISIBLE (450 6175);
FORCEADD Q_CAP..1
(2200 4550);
FORCEPROP 1 LAST LOCATION C2437
J 0
(2250 4650);
DISPLAY 0.489362 (2250 4650);
PAINT SKYBLUE (2250 4650);
FORCEPROP 2 LAST $SEC 1
J 0
(2250 4750);
DISPLAY 0.680851 (2250 4750);
PAINT MONO (2250 4750);
DISPLAY INVISIBLE (2250 4750);
FORCEPROP 2 LAST CDS_SEC 1
J 0
(2250 4750);
DISPLAY 1.021277 (2250 4750);
DISPLAY INVISIBLE (2250 4750);
FORCEPROP 1 LASTPIN (2200 4650) $PN 1
J 0
(2210 4630);
DISPLAY 0.489362 (2210 4630);
FORCEPROP 1 LASTPIN (2200 4450) $PN 2
J 0
(2210 4430);
DISPLAY 0.489362 (2210 4430);
FORCEPROP 1 LAST MATERIAL X6S
J 0
(2250 4450);
DISPLAY 0.489362 (2250 4450);
PAINT SKYBLUE (2250 4450);
FORCEPROP 1 LAST TOLERANCE 20%
J 0
(2250 4500);
DISPLAY 0.489362 (2250 4500);
PAINT SKYBLUE (2250 4500);
FORCEPROP 1 LAST VALUE 22UF
J 0
(2250 4600);
DISPLAY 0.489362 (2250 4600);
PAINT SKYBLUE (2250 4600);
FORCEPROP 1 LAST PART_NUMBER CH622KMEB02
J 0
(2250 4400);
DISPLAY 0.489362 (2250 4400);
PAINT SKYBLUE (2250 4400);
FORCEPROP 1 LAST VOLTAGE 4V
J 0
(2250 4550);
DISPLAY 0.489362 (2250 4550);
PAINT SKYBLUE (2250 4550);
FORCEPROP 1 LAST PACK_TYPE C0402
J 0
(2250 4350);
DISPLAY 0.489362 (2250 4350);
PAINT SKYBLUE (2250 4350);
FORCEPROP 2 LAST CDS_LIB pure_quanta
J 0
(2200 4550);
PAINT MONO (2200 4550);
DISPLAY INVISIBLE (2200 4550);
FORCEPROP 1 LAST PATH I64
J 0
(2250 4700);
DISPLAY 0.978723 (2250 4700);
PAINT WHITE (2250 4700);
DISPLAY INVISIBLE (2250 4700);
FORCEADD Q_CAP..1
(2650 4550);
FORCEPROP 1 LAST LOCATION C2444
J 0
(2700 4650);
DISPLAY 0.489362 (2700 4650);
PAINT SKYBLUE (2700 4650);
FORCEPROP 2 LAST $SEC 1
J 0
(2700 4750);
DISPLAY 0.680851 (2700 4750);
PAINT MONO (2700 4750);
DISPLAY INVISIBLE (2700 4750);
FORCEPROP 2 LAST CDS_SEC 1
J 0
(2700 4750);
DISPLAY 1.021277 (2700 4750);
DISPLAY INVISIBLE (2700 4750);
FORCEPROP 1 LASTPIN (2650 4650) $PN 1
J 0
(2660 4630);
DISPLAY 0.489362 (2660 4630);
FORCEPROP 1 LASTPIN (2650 4450) $PN 2
J 0
(2660 4430);
DISPLAY 0.489362 (2660 4430);
FORCEPROP 1 LAST MATERIAL X6S
J 0
(2700 4450);
DISPLAY 0.489362 (2700 4450);
PAINT SKYBLUE (2700 4450);
FORCEPROP 1 LAST TOLERANCE 20%
J 0
(2700 4500);
DISPLAY 0.489362 (2700 4500);
PAINT SKYBLUE (2700 4500);
FORCEPROP 1 LAST VALUE 22UF
J 0
(2700 4600);
DISPLAY 0.489362 (2700 4600);
PAINT SKYBLUE (2700 4600);
FORCEPROP 1 LAST PART_NUMBER CH622KMEB02
J 0
(2700 4400);
DISPLAY 0.489362 (2700 4400);
PAINT SKYBLUE (2700 4400);
FORCEPROP 1 LAST VOLTAGE 4V
J 0
(2700 4550);
DISPLAY 0.489362 (2700 4550);
PAINT SKYBLUE (2700 4550);
FORCEPROP 1 LAST PACK_TYPE C0402
J 0
(2700 4350);
DISPLAY 0.489362 (2700 4350);
PAINT SKYBLUE (2700 4350);
FORCEPROP 2 LAST CDS_LIB pure_quanta
J 0
(2650 4550);
PAINT MONO (2650 4550);
DISPLAY INVISIBLE (2650 4550);
FORCEPROP 1 LAST PATH I65
J 0
(2700 4700);
DISPLAY 0.978723 (2700 4700);
PAINT WHITE (2700 4700);
DISPLAY INVISIBLE (2700 4700);
FORCEADD Q_CAP..1
(2200 5225);
FORCEPROP 1 LAST LOCATION C2436
J 0
(2250 5325);
DISPLAY 0.489362 (2250 5325);
PAINT SKYBLUE (2250 5325);
FORCEPROP 2 LAST $SEC 1
J 0
(2250 5425);
DISPLAY 0.680851 (2250 5425);
PAINT MONO (2250 5425);
DISPLAY INVISIBLE (2250 5425);
FORCEPROP 2 LAST CDS_SEC 1
J 0
(2250 5425);
DISPLAY 1.021277 (2250 5425);
DISPLAY INVISIBLE (2250 5425);
FORCEPROP 1 LASTPIN (2200 5325) $PN 1
J 0
(2210 5305);
DISPLAY 0.489362 (2210 5305);
FORCEPROP 1 LASTPIN (2200 5125) $PN 2
J 0
(2210 5105);
DISPLAY 0.489362 (2210 5105);
FORCEPROP 1 LAST MATERIAL X6S
J 0
(2250 5125);
DISPLAY 0.489362 (2250 5125);
PAINT SKYBLUE (2250 5125);
FORCEPROP 1 LAST TOLERANCE 20%
J 0
(2250 5175);
DISPLAY 0.489362 (2250 5175);
PAINT SKYBLUE (2250 5175);
FORCEPROP 1 LAST VALUE 22UF
J 0
(2250 5275);
DISPLAY 0.489362 (2250 5275);
PAINT SKYBLUE (2250 5275);
FORCEPROP 1 LAST PART_NUMBER CH622KMEB02
J 0
(2250 5075);
DISPLAY 0.489362 (2250 5075);
PAINT SKYBLUE (2250 5075);
FORCEPROP 1 LAST VOLTAGE 4V
J 0
(2250 5225);
DISPLAY 0.489362 (2250 5225);
PAINT SKYBLUE (2250 5225);
FORCEPROP 1 LAST PACK_TYPE C0402
J 0
(2250 5025);
DISPLAY 0.489362 (2250 5025);
PAINT SKYBLUE (2250 5025);
FORCEPROP 2 LAST CDS_LIB pure_quanta
J 0
(2200 5225);
PAINT MONO (2200 5225);
DISPLAY INVISIBLE (2200 5225);
FORCEPROP 1 LAST PATH I66
J 0
(2250 5375);
DISPLAY 0.978723 (2250 5375);
PAINT WHITE (2250 5375);
DISPLAY INVISIBLE (2250 5375);
FORCEADD Q_CAP..1
(2650 5225);
FORCEPROP 1 LAST LOCATION C2443
J 0
(2700 5325);
DISPLAY 0.489362 (2700 5325);
PAINT SKYBLUE (2700 5325);
FORCEPROP 2 LAST $SEC 1
J 0
(2700 5425);
DISPLAY 0.680851 (2700 5425);
PAINT MONO (2700 5425);
DISPLAY INVISIBLE (2700 5425);
FORCEPROP 2 LAST CDS_SEC 1
J 0
(2700 5425);
DISPLAY 1.021277 (2700 5425);
DISPLAY INVISIBLE (2700 5425);
FORCEPROP 1 LASTPIN (2650 5325) $PN 1
J 0
(2660 5305);
DISPLAY 0.489362 (2660 5305);
FORCEPROP 1 LASTPIN (2650 5125) $PN 2
J 0
(2660 5105);
DISPLAY 0.489362 (2660 5105);
FORCEPROP 1 LAST MATERIAL X6S
J 0
(2700 5125);
DISPLAY 0.489362 (2700 5125);
PAINT SKYBLUE (2700 5125);
FORCEPROP 1 LAST TOLERANCE 20%
J 0
(2700 5175);
DISPLAY 0.489362 (2700 5175);
PAINT SKYBLUE (2700 5175);
FORCEPROP 1 LAST VALUE 22UF
J 0
(2700 5275);
DISPLAY 0.489362 (2700 5275);
PAINT SKYBLUE (2700 5275);
FORCEPROP 1 LAST PART_NUMBER CH622KMEB02
J 0
(2700 5075);
DISPLAY 0.489362 (2700 5075);
PAINT SKYBLUE (2700 5075);
FORCEPROP 1 LAST VOLTAGE 4V
J 0
(2700 5225);
DISPLAY 0.489362 (2700 5225);
PAINT SKYBLUE (2700 5225);
FORCEPROP 1 LAST PACK_TYPE C0402
J 0
(2700 5025);
DISPLAY 0.489362 (2700 5025);
PAINT SKYBLUE (2700 5025);
FORCEPROP 2 LAST CDS_LIB pure_quanta
J 0
(2650 5225);
PAINT MONO (2650 5225);
DISPLAY INVISIBLE (2650 5225);
FORCEPROP 1 LAST PATH I67
J 0
(2700 5375);
DISPLAY 0.978723 (2700 5375);
PAINT WHITE (2700 5375);
DISPLAY INVISIBLE (2700 5375);
FORCEADD Q_CAP..1
(3100 5875);
FORCEPROP 1 LAST LOCATION C2449
J 0
(3150 5975);
DISPLAY 0.489362 (3150 5975);
PAINT SKYBLUE (3150 5975);
FORCEPROP 2 LAST $SEC 1
J 0
(3150 6075);
DISPLAY 0.680851 (3150 6075);
PAINT MONO (3150 6075);
DISPLAY INVISIBLE (3150 6075);
FORCEPROP 2 LAST CDS_SEC 1
J 0
(3150 6075);
DISPLAY 1.021277 (3150 6075);
DISPLAY INVISIBLE (3150 6075);
FORCEPROP 1 LASTPIN (3100 5975) $PN 1
J 0
(3110 5955);
DISPLAY 0.489362 (3110 5955);
FORCEPROP 1 LASTPIN (3100 5775) $PN 2
J 0
(3110 5755);
DISPLAY 0.489362 (3110 5755);
FORCEPROP 1 LAST MATERIAL X6S
J 0
(3150 5775);
DISPLAY 0.489362 (3150 5775);
PAINT SKYBLUE (3150 5775);
FORCEPROP 1 LAST TOLERANCE 20%
J 0
(3150 5825);
DISPLAY 0.489362 (3150 5825);
PAINT SKYBLUE (3150 5825);
FORCEPROP 1 LAST VALUE 22UF
J 0
(3150 5925);
DISPLAY 0.489362 (3150 5925);
PAINT SKYBLUE (3150 5925);
FORCEPROP 1 LAST PART_NUMBER CH622KMEB02
J 0
(3150 5725);
DISPLAY 0.489362 (3150 5725);
PAINT SKYBLUE (3150 5725);
FORCEPROP 1 LAST VOLTAGE 4V
J 0
(3150 5875);
DISPLAY 0.489362 (3150 5875);
PAINT SKYBLUE (3150 5875);
FORCEPROP 1 LAST PACK_TYPE C0402
J 0
(3150 5675);
DISPLAY 0.489362 (3150 5675);
PAINT SKYBLUE (3150 5675);
FORCEPROP 2 LAST CDS_LIB pure_quanta
J 0
(3100 5875);
PAINT MONO (3100 5875);
DISPLAY INVISIBLE (3100 5875);
FORCEPROP 1 LAST PATH I68
J 0
(3150 6025);
DISPLAY 0.978723 (3150 6025);
PAINT WHITE (3150 6025);
DISPLAY INVISIBLE (3150 6025);
FORCEADD Q_CAP..1
(3100 5225);
FORCEPROP 1 LAST LOCATION C2450
J 0
(3150 5325);
DISPLAY 0.489362 (3150 5325);
PAINT SKYBLUE (3150 5325);
FORCEPROP 2 LAST $SEC 1
J 0
(3150 5425);
DISPLAY 0.680851 (3150 5425);
PAINT MONO (3150 5425);
DISPLAY INVISIBLE (3150 5425);
FORCEPROP 2 LAST CDS_SEC 1
J 0
(3150 5425);
DISPLAY 1.021277 (3150 5425);
DISPLAY INVISIBLE (3150 5425);
FORCEPROP 1 LASTPIN (3100 5325) $PN 1
J 0
(3110 5305);
DISPLAY 0.489362 (3110 5305);
FORCEPROP 1 LASTPIN (3100 5125) $PN 2
J 0
(3110 5105);
DISPLAY 0.489362 (3110 5105);
FORCEPROP 1 LAST MATERIAL X6S
J 0
(3150 5125);
DISPLAY 0.489362 (3150 5125);
PAINT SKYBLUE (3150 5125);
FORCEPROP 1 LAST TOLERANCE 20%
J 0
(3150 5175);
DISPLAY 0.489362 (3150 5175);
PAINT SKYBLUE (3150 5175);
FORCEPROP 1 LAST VALUE 22UF
J 0
(3150 5275);
DISPLAY 0.489362 (3150 5275);
PAINT SKYBLUE (3150 5275);
FORCEPROP 1 LAST PART_NUMBER CH622KMEB02
J 0
(3150 5075);
DISPLAY 0.489362 (3150 5075);
PAINT SKYBLUE (3150 5075);
FORCEPROP 1 LAST VOLTAGE 4V
J 0
(3150 5225);
DISPLAY 0.489362 (3150 5225);
PAINT SKYBLUE (3150 5225);
FORCEPROP 1 LAST PACK_TYPE C0402
J 0
(3150 5025);
DISPLAY 0.489362 (3150 5025);
PAINT SKYBLUE (3150 5025);
FORCEPROP 2 LAST CDS_LIB pure_quanta
J 0
(3100 5225);
PAINT MONO (3100 5225);
DISPLAY INVISIBLE (3100 5225);
FORCEPROP 1 LAST PATH I69
J 0
(3150 5375);
DISPLAY 0.978723 (3150 5375);
PAINT WHITE (3150 5375);
DISPLAY INVISIBLE (3150 5375);
FORCEADD Q_CAP..1
(1300 1800);
FORCEPROP 1 LAST LOCATION C2427
J 0
(1350 1900);
DISPLAY 0.489362 (1350 1900);
PAINT SKYBLUE (1350 1900);
FORCEPROP 2 LAST $SEC 1
J 0
(1350 2000);
DISPLAY 0.680851 (1350 2000);
PAINT MONO (1350 2000);
DISPLAY INVISIBLE (1350 2000);
FORCEPROP 2 LAST CDS_SEC 1
J 0
(1350 2000);
DISPLAY 1.021277 (1350 2000);
DISPLAY INVISIBLE (1350 2000);
FORCEPROP 1 LASTPIN (1300 1900) $PN 1
J 0
(1310 1880);
DISPLAY 0.489362 (1310 1880);
FORCEPROP 1 LASTPIN (1300 1700) $PN 2
J 0
(1310 1680);
DISPLAY 0.489362 (1310 1680);
FORCEPROP 1 LAST MATERIAL X6S
J 0
(1350 1700);
DISPLAY 0.489362 (1350 1700);
PAINT SKYBLUE (1350 1700);
FORCEPROP 1 LAST TOLERANCE 20%
J 0
(1350 1750);
DISPLAY 0.489362 (1350 1750);
PAINT SKYBLUE (1350 1750);
FORCEPROP 1 LAST VALUE 22UF
J 0
(1350 1850);
DISPLAY 0.489362 (1350 1850);
PAINT SKYBLUE (1350 1850);
FORCEPROP 1 LAST PART_NUMBER CH622KMEB02
J 0
(1350 1650);
DISPLAY 0.489362 (1350 1650);
PAINT SKYBLUE (1350 1650);
FORCEPROP 1 LAST VOLTAGE 4V
J 0
(1350 1800);
DISPLAY 0.489362 (1350 1800);
PAINT SKYBLUE (1350 1800);
FORCEPROP 1 LAST PACK_TYPE C0402
J 0
(1350 1600);
DISPLAY 0.489362 (1350 1600);
PAINT SKYBLUE (1350 1600);
FORCEPROP 2 LAST CDS_LIB pure_quanta
J 0
(1300 1800);
PAINT MONO (1300 1800);
DISPLAY INVISIBLE (1300 1800);
FORCEPROP 1 LAST PATH I7
J 0
(1350 1950);
DISPLAY 0.978723 (1350 1950);
PAINT WHITE (1350 1950);
DISPLAY INVISIBLE (1350 1950);
FORCEADD Q_CAP..1
(3100 4550);
FORCEPROP 1 LAST LOCATION C2451
J 0
(3150 4650);
DISPLAY 0.489362 (3150 4650);
PAINT SKYBLUE (3150 4650);
FORCEPROP 2 LAST $SEC 1
J 0
(3150 4750);
DISPLAY 0.680851 (3150 4750);
PAINT MONO (3150 4750);
DISPLAY INVISIBLE (3150 4750);
FORCEPROP 2 LAST CDS_SEC 1
J 0
(3150 4750);
DISPLAY 1.021277 (3150 4750);
DISPLAY INVISIBLE (3150 4750);
FORCEPROP 1 LASTPIN (3100 4650) $PN 1
J 0
(3110 4630);
DISPLAY 0.489362 (3110 4630);
FORCEPROP 1 LASTPIN (3100 4450) $PN 2
J 0
(3110 4430);
DISPLAY 0.489362 (3110 4430);
FORCEPROP 1 LAST MATERIAL X6S
J 0
(3150 4450);
DISPLAY 0.489362 (3150 4450);
PAINT SKYBLUE (3150 4450);
FORCEPROP 1 LAST TOLERANCE 20%
J 0
(3150 4500);
DISPLAY 0.489362 (3150 4500);
PAINT SKYBLUE (3150 4500);
FORCEPROP 1 LAST VALUE 22UF
J 0
(3150 4600);
DISPLAY 0.489362 (3150 4600);
PAINT SKYBLUE (3150 4600);
FORCEPROP 1 LAST PART_NUMBER CH622KMEB02
J 0
(3150 4400);
DISPLAY 0.489362 (3150 4400);
PAINT SKYBLUE (3150 4400);
FORCEPROP 1 LAST VOLTAGE 4V
J 0
(3150 4550);
DISPLAY 0.489362 (3150 4550);
PAINT SKYBLUE (3150 4550);
FORCEPROP 1 LAST PACK_TYPE C0402
J 0
(3150 4350);
DISPLAY 0.489362 (3150 4350);
PAINT SKYBLUE (3150 4350);
FORCEPROP 2 LAST CDS_LIB pure_quanta
J 0
(3100 4550);
PAINT MONO (3100 4550);
DISPLAY INVISIBLE (3100 4550);
FORCEPROP 1 LAST PATH I70
J 0
(3150 4700);
DISPLAY 0.978723 (3150 4700);
PAINT WHITE (3150 4700);
DISPLAY INVISIBLE (3150 4700);
FORCEADD Q_CAP..1
(3550 4550);
FORCEPROP 1 LAST LOCATION C2458
J 0
(3600 4650);
DISPLAY 0.489362 (3600 4650);
PAINT SKYBLUE (3600 4650);
FORCEPROP 2 LAST $SEC 1
J 0
(3600 4750);
DISPLAY 0.680851 (3600 4750);
PAINT MONO (3600 4750);
DISPLAY INVISIBLE (3600 4750);
FORCEPROP 2 LAST CDS_SEC 1
J 0
(3600 4750);
DISPLAY 1.021277 (3600 4750);
DISPLAY INVISIBLE (3600 4750);
FORCEPROP 1 LASTPIN (3550 4650) $PN 1
J 0
(3560 4630);
DISPLAY 0.489362 (3560 4630);
FORCEPROP 1 LASTPIN (3550 4450) $PN 2
J 0
(3560 4430);
DISPLAY 0.489362 (3560 4430);
FORCEPROP 1 LAST MATERIAL X6S
J 0
(3600 4450);
DISPLAY 0.489362 (3600 4450);
PAINT SKYBLUE (3600 4450);
FORCEPROP 1 LAST TOLERANCE 20%
J 0
(3600 4500);
DISPLAY 0.489362 (3600 4500);
PAINT SKYBLUE (3600 4500);
FORCEPROP 1 LAST VALUE 22UF
J 0
(3600 4600);
DISPLAY 0.489362 (3600 4600);
PAINT SKYBLUE (3600 4600);
FORCEPROP 1 LAST PART_NUMBER CH622KMEB02
J 0
(3600 4400);
DISPLAY 0.489362 (3600 4400);
PAINT SKYBLUE (3600 4400);
FORCEPROP 1 LAST VOLTAGE 4V
J 0
(3600 4550);
DISPLAY 0.489362 (3600 4550);
PAINT SKYBLUE (3600 4550);
FORCEPROP 1 LAST PACK_TYPE C0402
J 0
(3600 4350);
DISPLAY 0.489362 (3600 4350);
PAINT SKYBLUE (3600 4350);
FORCEPROP 2 LAST CDS_LIB pure_quanta
J 0
(3550 4550);
PAINT MONO (3550 4550);
DISPLAY INVISIBLE (3550 4550);
FORCEPROP 1 LAST PATH I71
J 0
(3600 4700);
DISPLAY 0.978723 (3600 4700);
PAINT WHITE (3600 4700);
DISPLAY INVISIBLE (3600 4700);
FORCEADD Q_CAP..1
(4000 4550);
FORCEPROP 1 LAST LOCATION C2465
J 0
(4050 4650);
DISPLAY 0.489362 (4050 4650);
PAINT SKYBLUE (4050 4650);
FORCEPROP 2 LAST $SEC 1
J 0
(4050 4750);
DISPLAY 0.680851 (4050 4750);
PAINT MONO (4050 4750);
DISPLAY INVISIBLE (4050 4750);
FORCEPROP 2 LAST CDS_SEC 1
J 0
(4050 4750);
DISPLAY 1.021277 (4050 4750);
DISPLAY INVISIBLE (4050 4750);
FORCEPROP 1 LASTPIN (4000 4650) $PN 1
J 0
(4010 4630);
DISPLAY 0.489362 (4010 4630);
FORCEPROP 1 LASTPIN (4000 4450) $PN 2
J 0
(4010 4430);
DISPLAY 0.489362 (4010 4430);
FORCEPROP 1 LAST MATERIAL X6S
J 0
(4050 4450);
DISPLAY 0.489362 (4050 4450);
PAINT SKYBLUE (4050 4450);
FORCEPROP 1 LAST TOLERANCE 20%
J 0
(4050 4500);
DISPLAY 0.489362 (4050 4500);
PAINT SKYBLUE (4050 4500);
FORCEPROP 1 LAST VALUE 22UF
J 0
(4050 4600);
DISPLAY 0.489362 (4050 4600);
PAINT SKYBLUE (4050 4600);
FORCEPROP 1 LAST PART_NUMBER CH622KMEB02
J 0
(4050 4400);
DISPLAY 0.489362 (4050 4400);
PAINT SKYBLUE (4050 4400);
FORCEPROP 1 LAST VOLTAGE 4V
J 0
(4050 4550);
DISPLAY 0.489362 (4050 4550);
PAINT SKYBLUE (4050 4550);
FORCEPROP 1 LAST PACK_TYPE C0402
J 0
(4050 4350);
DISPLAY 0.489362 (4050 4350);
PAINT SKYBLUE (4050 4350);
FORCEPROP 2 LAST CDS_LIB pure_quanta
J 0
(4000 4550);
PAINT MONO (4000 4550);
DISPLAY INVISIBLE (4000 4550);
FORCEPROP 1 LAST PATH I72
J 0
(4050 4700);
DISPLAY 0.978723 (4050 4700);
PAINT WHITE (4050 4700);
DISPLAY INVISIBLE (4050 4700);
FORCEADD Q_CAP..1
(3550 5225);
FORCEPROP 1 LAST LOCATION C2457
J 0
(3600 5325);
DISPLAY 0.489362 (3600 5325);
PAINT SKYBLUE (3600 5325);
FORCEPROP 2 LAST $SEC 1
J 0
(3600 5425);
DISPLAY 0.680851 (3600 5425);
PAINT MONO (3600 5425);
DISPLAY INVISIBLE (3600 5425);
FORCEPROP 2 LAST CDS_SEC 1
J 0
(3600 5425);
DISPLAY 1.021277 (3600 5425);
DISPLAY INVISIBLE (3600 5425);
FORCEPROP 1 LASTPIN (3550 5325) $PN 1
J 0
(3560 5305);
DISPLAY 0.489362 (3560 5305);
FORCEPROP 1 LASTPIN (3550 5125) $PN 2
J 0
(3560 5105);
DISPLAY 0.489362 (3560 5105);
FORCEPROP 1 LAST MATERIAL X6S
J 0
(3600 5125);
DISPLAY 0.489362 (3600 5125);
PAINT SKYBLUE (3600 5125);
FORCEPROP 1 LAST TOLERANCE 20%
J 0
(3600 5175);
DISPLAY 0.489362 (3600 5175);
PAINT SKYBLUE (3600 5175);
FORCEPROP 1 LAST VALUE 22UF
J 0
(3600 5275);
DISPLAY 0.489362 (3600 5275);
PAINT SKYBLUE (3600 5275);
FORCEPROP 1 LAST PART_NUMBER CH622KMEB02
J 0
(3600 5075);
DISPLAY 0.489362 (3600 5075);
PAINT SKYBLUE (3600 5075);
FORCEPROP 1 LAST VOLTAGE 4V
J 0
(3600 5225);
DISPLAY 0.489362 (3600 5225);
PAINT SKYBLUE (3600 5225);
FORCEPROP 1 LAST PACK_TYPE C0402
J 0
(3600 5025);
DISPLAY 0.489362 (3600 5025);
PAINT SKYBLUE (3600 5025);
FORCEPROP 2 LAST CDS_LIB pure_quanta
J 0
(3550 5225);
PAINT MONO (3550 5225);
DISPLAY INVISIBLE (3550 5225);
FORCEPROP 1 LAST PATH I73
J 0
(3600 5375);
DISPLAY 0.978723 (3600 5375);
PAINT WHITE (3600 5375);
DISPLAY INVISIBLE (3600 5375);
FORCEADD Q_CAP..1
(3550 5875);
FORCEPROP 1 LAST LOCATION C2456
J 0
(3600 5975);
DISPLAY 0.489362 (3600 5975);
PAINT SKYBLUE (3600 5975);
FORCEPROP 2 LAST $SEC 1
J 0
(3600 6075);
DISPLAY 0.680851 (3600 6075);
PAINT MONO (3600 6075);
DISPLAY INVISIBLE (3600 6075);
FORCEPROP 2 LAST CDS_SEC 1
J 0
(3600 6075);
DISPLAY 1.021277 (3600 6075);
DISPLAY INVISIBLE (3600 6075);
FORCEPROP 1 LASTPIN (3550 5975) $PN 1
J 0
(3560 5955);
DISPLAY 0.489362 (3560 5955);
FORCEPROP 1 LASTPIN (3550 5775) $PN 2
J 0
(3560 5755);
DISPLAY 0.489362 (3560 5755);
FORCEPROP 1 LAST MATERIAL X6S
J 0
(3600 5775);
DISPLAY 0.489362 (3600 5775);
PAINT SKYBLUE (3600 5775);
FORCEPROP 1 LAST TOLERANCE 20%
J 0
(3600 5825);
DISPLAY 0.489362 (3600 5825);
PAINT SKYBLUE (3600 5825);
FORCEPROP 1 LAST VALUE 22UF
J 0
(3600 5925);
DISPLAY 0.489362 (3600 5925);
PAINT SKYBLUE (3600 5925);
FORCEPROP 1 LAST PART_NUMBER CH622KMEB02
J 0
(3600 5725);
DISPLAY 0.489362 (3600 5725);
PAINT SKYBLUE (3600 5725);
FORCEPROP 1 LAST VOLTAGE 4V
J 0
(3600 5875);
DISPLAY 0.489362 (3600 5875);
PAINT SKYBLUE (3600 5875);
FORCEPROP 1 LAST PACK_TYPE C0402
J 0
(3600 5675);
DISPLAY 0.489362 (3600 5675);
PAINT SKYBLUE (3600 5675);
FORCEPROP 2 LAST CDS_LIB pure_quanta
J 0
(3550 5875);
PAINT MONO (3550 5875);
DISPLAY INVISIBLE (3550 5875);
FORCEPROP 1 LAST PATH I74
J 0
(3600 6025);
DISPLAY 0.978723 (3600 6025);
PAINT WHITE (3600 6025);
DISPLAY INVISIBLE (3600 6025);
FORCEADD Q_CAP..1
(4000 5225);
FORCEPROP 1 LAST LOCATION C2464
J 0
(4050 5325);
DISPLAY 0.489362 (4050 5325);
PAINT SKYBLUE (4050 5325);
FORCEPROP 2 LAST $SEC 1
J 0
(4050 5425);
DISPLAY 0.680851 (4050 5425);
PAINT MONO (4050 5425);
DISPLAY INVISIBLE (4050 5425);
FORCEPROP 2 LAST CDS_SEC 1
J 0
(4050 5425);
DISPLAY 1.021277 (4050 5425);
DISPLAY INVISIBLE (4050 5425);
FORCEPROP 1 LASTPIN (4000 5325) $PN 1
J 0
(4010 5305);
DISPLAY 0.489362 (4010 5305);
FORCEPROP 1 LASTPIN (4000 5125) $PN 2
J 0
(4010 5105);
DISPLAY 0.489362 (4010 5105);
FORCEPROP 1 LAST MATERIAL X6S
J 0
(4050 5125);
DISPLAY 0.489362 (4050 5125);
PAINT SKYBLUE (4050 5125);
FORCEPROP 1 LAST TOLERANCE 20%
J 0
(4050 5175);
DISPLAY 0.489362 (4050 5175);
PAINT SKYBLUE (4050 5175);
FORCEPROP 1 LAST VALUE 22UF
J 0
(4050 5275);
DISPLAY 0.489362 (4050 5275);
PAINT SKYBLUE (4050 5275);
FORCEPROP 1 LAST PART_NUMBER CH622KMEB02
J 0
(4050 5075);
DISPLAY 0.489362 (4050 5075);
PAINT SKYBLUE (4050 5075);
FORCEPROP 1 LAST VOLTAGE 4V
J 0
(4050 5225);
DISPLAY 0.489362 (4050 5225);
PAINT SKYBLUE (4050 5225);
FORCEPROP 1 LAST PACK_TYPE C0402
J 0
(4050 5025);
DISPLAY 0.489362 (4050 5025);
PAINT SKYBLUE (4050 5025);
FORCEPROP 2 LAST CDS_LIB pure_quanta
J 0
(4000 5225);
PAINT MONO (4000 5225);
DISPLAY INVISIBLE (4000 5225);
FORCEPROP 1 LAST PATH I75
J 0
(4050 5375);
DISPLAY 0.978723 (4050 5375);
PAINT WHITE (4050 5375);
DISPLAY INVISIBLE (4050 5375);
FORCEADD Q_CAP..1
(4000 5875);
FORCEPROP 1 LAST LOCATION C2463
J 0
(4050 5975);
DISPLAY 0.489362 (4050 5975);
PAINT SKYBLUE (4050 5975);
FORCEPROP 2 LAST $SEC 1
J 0
(4050 6075);
DISPLAY 0.680851 (4050 6075);
PAINT MONO (4050 6075);
DISPLAY INVISIBLE (4050 6075);
FORCEPROP 2 LAST CDS_SEC 1
J 0
(4050 6075);
DISPLAY 1.021277 (4050 6075);
DISPLAY INVISIBLE (4050 6075);
FORCEPROP 1 LASTPIN (4000 5975) $PN 1
J 0
(4010 5955);
DISPLAY 0.489362 (4010 5955);
FORCEPROP 1 LASTPIN (4000 5775) $PN 2
J 0
(4010 5755);
DISPLAY 0.489362 (4010 5755);
FORCEPROP 1 LAST MATERIAL X6S
J 0
(4050 5775);
DISPLAY 0.489362 (4050 5775);
PAINT SKYBLUE (4050 5775);
FORCEPROP 1 LAST TOLERANCE 20%
J 0
(4050 5825);
DISPLAY 0.489362 (4050 5825);
PAINT SKYBLUE (4050 5825);
FORCEPROP 1 LAST VALUE 22UF
J 0
(4050 5925);
DISPLAY 0.489362 (4050 5925);
PAINT SKYBLUE (4050 5925);
FORCEPROP 1 LAST PART_NUMBER CH622KMEB02
J 0
(4050 5725);
DISPLAY 0.489362 (4050 5725);
PAINT SKYBLUE (4050 5725);
FORCEPROP 1 LAST VOLTAGE 4V
J 0
(4050 5875);
DISPLAY 0.489362 (4050 5875);
PAINT SKYBLUE (4050 5875);
FORCEPROP 1 LAST PACK_TYPE C0402
J 0
(4050 5675);
DISPLAY 0.489362 (4050 5675);
PAINT SKYBLUE (4050 5675);
FORCEPROP 2 LAST CDS_LIB pure_quanta
J 0
(4000 5875);
PAINT MONO (4000 5875);
DISPLAY INVISIBLE (4000 5875);
FORCEPROP 1 LAST PATH I76
J 0
(4050 6025);
DISPLAY 0.978723 (4050 6025);
PAINT WHITE (4050 6025);
DISPLAY INVISIBLE (4050 6025);
FORCEADD Q_CAP..1
(5000 775);
FORCEPROP 1 LAST LOCATION C3919
J 0
(5050 875);
DISPLAY 0.489362 (5050 875);
PAINT SKYBLUE (5050 875);
FORCEPROP 2 LAST $SEC 1
J 0
(5050 975);
DISPLAY 0.680851 (5050 975);
PAINT MONO (5050 975);
DISPLAY INVISIBLE (5050 975);
FORCEPROP 2 LAST CDS_SEC 1
J 0
(5050 975);
DISPLAY 1.021277 (5050 975);
DISPLAY INVISIBLE (5050 975);
FORCEPROP 1 LASTPIN (5000 875) $PN 1
J 0
(5010 855);
DISPLAY 0.489362 (5010 855);
FORCEPROP 1 LASTPIN (5000 675) $PN 2
J 0
(5010 655);
DISPLAY 0.489362 (5010 655);
FORCEPROP 1 LAST MATERIAL X6S
J 0
(5050 675);
DISPLAY 0.489362 (5050 675);
PAINT SKYBLUE (5050 675);
FORCEPROP 1 LAST TOLERANCE 20%
J 0
(5050 725);
DISPLAY 0.489362 (5050 725);
PAINT SKYBLUE (5050 725);
FORCEPROP 1 LAST VALUE 22UF
J 0
(5050 825);
DISPLAY 0.489362 (5050 825);
PAINT SKYBLUE (5050 825);
FORCEPROP 1 LAST PART_NUMBER CH622KMEB02
J 0
(5050 625);
DISPLAY 0.489362 (5050 625);
PAINT SKYBLUE (5050 625);
FORCEPROP 1 LAST VOLTAGE 4V
J 0
(5050 775);
DISPLAY 0.489362 (5050 775);
PAINT SKYBLUE (5050 775);
FORCEPROP 1 LAST PACK_TYPE C0402
J 0
(5050 575);
DISPLAY 0.489362 (5050 575);
PAINT SKYBLUE (5050 575);
FORCEPROP 2 LAST CDS_LIB pure_quanta
J 0
(5000 775);
PAINT MONO (5000 775);
DISPLAY INVISIBLE (5000 775);
FORCEPROP 1 LAST PATH I77
J 0
(5050 925);
DISPLAY 0.978723 (5050 925);
PAINT WHITE (5050 925);
DISPLAY INVISIBLE (5050 925);
FORCEADD UNIVERSAL_GND..1
(4400 1425);
FORCEPROP 3 LASTPIN (4400 1475) SIG_NAME GND\g
J 0
(4410 1485);
DISPLAY 0.659574 (4410 1485);
PAINT MONO (4410 1485);
DISPLAY INVISIBLE (4410 1485);
FORCEPROP 2 LAST CDS_LIB pure_quanta_power
J 0
(4400 1425);
PAINT MONO (4400 1425);
DISPLAY INVISIBLE (4400 1425);
FORCEPROP 1 LAST PATH I78
J 0
(4475 1425);
DISPLAY 0.872340 (4475 1425);
PAINT AQUA (4475 1425);
DISPLAY INVISIBLE (4475 1425);
FORCEPROP 1 LAST HDL_POWER GND
J 1
(4425 1350);
DISPLAY 0.872340 (4425 1350);
PAINT GREEN (4425 1350);
DISPLAY INVISIBLE (4425 1350);
FORCEADD Q_CAP..1
(4400 1800);
FORCEPROP 1 LAST LOCATION C2476
J 0
(4450 1900);
DISPLAY 0.489362 (4450 1900);
PAINT SKYBLUE (4450 1900);
FORCEPROP 2 LAST $SEC 1
J 0
(4450 2000);
DISPLAY 0.680851 (4450 2000);
PAINT MONO (4450 2000);
DISPLAY INVISIBLE (4450 2000);
FORCEPROP 2 LAST CDS_SEC 1
J 0
(4450 2000);
DISPLAY 1.021277 (4450 2000);
DISPLAY INVISIBLE (4450 2000);
FORCEPROP 1 LASTPIN (4400 1900) $PN 1
J 0
(4410 1880);
DISPLAY 0.489362 (4410 1880);
FORCEPROP 1 LASTPIN (4400 1700) $PN 2
J 0
(4410 1680);
DISPLAY 0.489362 (4410 1680);
FORCEPROP 1 LAST MATERIAL X6S
J 0
(4450 1700);
DISPLAY 0.489362 (4450 1700);
PAINT SKYBLUE (4450 1700);
FORCEPROP 1 LAST TOLERANCE 20%
J 0
(4450 1750);
DISPLAY 0.489362 (4450 1750);
PAINT SKYBLUE (4450 1750);
FORCEPROP 1 LAST VALUE 22UF
J 0
(4450 1850);
DISPLAY 0.489362 (4450 1850);
PAINT SKYBLUE (4450 1850);
FORCEPROP 1 LAST PART_NUMBER CH622KMEB02
J 0
(4450 1650);
DISPLAY 0.489362 (4450 1650);
PAINT SKYBLUE (4450 1650);
FORCEPROP 1 LAST VOLTAGE 4V
J 0
(4450 1800);
DISPLAY 0.489362 (4450 1800);
PAINT SKYBLUE (4450 1800);
FORCEPROP 1 LAST PACK_TYPE C0402
J 0
(4450 1600);
DISPLAY 0.489362 (4450 1600);
PAINT SKYBLUE (4450 1600);
FORCEPROP 2 LAST CDS_LIB pure_quanta
J 0
(4400 1800);
PAINT MONO (4400 1800);
DISPLAY INVISIBLE (4400 1800);
FORCEPROP 1 LAST PATH I79
J 0
(4450 1950);
DISPLAY 0.978723 (4450 1950);
PAINT WHITE (4450 1950);
DISPLAY INVISIBLE (4450 1950);
FORCEADD Q_CAP..1
(1750 1075);
FORCEPROP 1 LAST LOCATION C3915
J 0
(1800 1175);
DISPLAY 0.489362 (1800 1175);
PAINT SKYBLUE (1800 1175);
FORCEPROP 2 LAST $SEC 1
J 0
(1800 1275);
DISPLAY 0.680851 (1800 1275);
PAINT MONO (1800 1275);
DISPLAY INVISIBLE (1800 1275);
FORCEPROP 2 LAST CDS_SEC 1
J 0
(1800 1275);
DISPLAY 1.021277 (1800 1275);
DISPLAY INVISIBLE (1800 1275);
FORCEPROP 1 LASTPIN (1750 1175) $PN 1
J 0
(1760 1155);
DISPLAY 0.489362 (1760 1155);
FORCEPROP 1 LASTPIN (1750 975) $PN 2
J 0
(1760 955);
DISPLAY 0.489362 (1760 955);
FORCEPROP 1 LAST MATERIAL X6S
J 0
(1800 975);
DISPLAY 0.489362 (1800 975);
PAINT SKYBLUE (1800 975);
FORCEPROP 1 LAST TOLERANCE 20%
J 0
(1800 1025);
DISPLAY 0.489362 (1800 1025);
PAINT SKYBLUE (1800 1025);
FORCEPROP 1 LAST VALUE 22UF
J 0
(1800 1125);
DISPLAY 0.489362 (1800 1125);
PAINT SKYBLUE (1800 1125);
FORCEPROP 1 LAST PART_NUMBER CH622KMEB02
J 0
(1800 925);
DISPLAY 0.489362 (1800 925);
PAINT SKYBLUE (1800 925);
FORCEPROP 1 LAST VOLTAGE 4V
J 0
(1800 1075);
DISPLAY 0.489362 (1800 1075);
PAINT SKYBLUE (1800 1075);
FORCEPROP 1 LAST PACK_TYPE C0402
J 0
(1800 875);
DISPLAY 0.489362 (1800 875);
PAINT SKYBLUE (1800 875);
FORCEPROP 2 LAST CDS_LIB pure_quanta
J 0
(1750 1075);
PAINT MONO (1750 1075);
DISPLAY INVISIBLE (1750 1075);
FORCEPROP 1 LAST PATH I8
J 0
(1800 1225);
DISPLAY 0.978723 (1800 1225);
PAINT WHITE (1800 1225);
DISPLAY INVISIBLE (1800 1225);
FORCEADD UNIVERSAL_POWER..1
(5000 1050);
FORCEPROP 3 LASTPIN (5000 1000) SIG_NAME PVDD11_S3_P1\g
J 0
(5010 1010);
DISPLAY 0.659574 (5010 1010);
PAINT MONO (5010 1010);
DISPLAY INVISIBLE (5010 1010);
FORCEPROP 1 LAST HDL_POWER PVDD11_S3_P1
J 1
(5000 1100);
DISPLAY 0.489362 (5000 1100);
PAINT GREEN (5000 1100);
FORCEPROP 2 LAST CDS_LIB pure_quanta_power
J 0
(5000 1050);
DISPLAY INVISIBLE (5000 1050);
FORCEPROP 1 LAST PATH I80
J 0
(5050 1075);
DISPLAY 0.872340 (5050 1075);
PAINT AQUA (5050 1075);
DISPLAY INVISIBLE (5050 1075);
FORCEADD Q_CAP..1
(5000 1375);
FORCEPROP 1 LAST LOCATION C2483
J 0
(5050 1475);
DISPLAY 0.489362 (5050 1475);
PAINT SKYBLUE (5050 1475);
FORCEPROP 2 LAST $SEC 1
J 0
(5050 1575);
DISPLAY 0.680851 (5050 1575);
PAINT MONO (5050 1575);
DISPLAY INVISIBLE (5050 1575);
FORCEPROP 2 LAST CDS_SEC 1
J 0
(5050 1575);
DISPLAY 1.021277 (5050 1575);
DISPLAY INVISIBLE (5050 1575);
FORCEPROP 1 LASTPIN (5000 1475) $PN 1
J 0
(5010 1455);
DISPLAY 0.489362 (5010 1455);
FORCEPROP 1 LASTPIN (5000 1275) $PN 2
J 0
(5010 1255);
DISPLAY 0.489362 (5010 1255);
FORCEPROP 1 LAST MATERIAL X6S
J 0
(5050 1275);
DISPLAY 0.489362 (5050 1275);
PAINT SKYBLUE (5050 1275);
FORCEPROP 1 LAST TOLERANCE 20%
J 0
(5050 1325);
DISPLAY 0.489362 (5050 1325);
PAINT SKYBLUE (5050 1325);
FORCEPROP 1 LAST VALUE 22UF
J 0
(5050 1425);
DISPLAY 0.489362 (5050 1425);
PAINT SKYBLUE (5050 1425);
FORCEPROP 1 LAST PART_NUMBER CH622KMEB02
J 0
(5050 1225);
DISPLAY 0.489362 (5050 1225);
PAINT SKYBLUE (5050 1225);
FORCEPROP 1 LAST VOLTAGE 4V
J 0
(5050 1375);
DISPLAY 0.489362 (5050 1375);
PAINT SKYBLUE (5050 1375);
FORCEPROP 1 LAST PACK_TYPE C0402
J 0
(5050 1175);
DISPLAY 0.489362 (5050 1175);
PAINT SKYBLUE (5050 1175);
FORCEPROP 2 LAST CDS_LIB pure_quanta
J 0
(5000 1375);
PAINT MONO (5000 1375);
DISPLAY INVISIBLE (5000 1375);
FORCEPROP 1 LAST PATH I81
J 0
(5050 1525);
DISPLAY 0.978723 (5050 1525);
PAINT WHITE (5050 1525);
DISPLAY INVISIBLE (5050 1525);
FORCEADD UNIVERSAL_POWER..1
(5000 1650);
FORCEPROP 3 LASTPIN (5000 1600) SIG_NAME PVDD11_S3_P1\g
J 0
(5010 1610);
DISPLAY 0.659574 (5010 1610);
PAINT MONO (5010 1610);
DISPLAY INVISIBLE (5010 1610);
FORCEPROP 1 LAST HDL_POWER PVDD11_S3_P1
J 1
(5000 1700);
DISPLAY 0.489362 (5000 1700);
PAINT GREEN (5000 1700);
FORCEPROP 2 LAST CDS_LIB pure_quanta_power
J 0
(5000 1650);
DISPLAY INVISIBLE (5000 1650);
FORCEPROP 1 LAST PATH I82
J 0
(5050 1675);
DISPLAY 0.872340 (5050 1675);
PAINT AQUA (5050 1675);
DISPLAY INVISIBLE (5050 1675);
FORCEADD UNIVERSAL_GND..1
(5450 450);
FORCEPROP 3 LASTPIN (5450 500) SIG_NAME GND\g
J 0
(5460 510);
DISPLAY 0.659574 (5460 510);
PAINT MONO (5460 510);
DISPLAY INVISIBLE (5460 510);
FORCEPROP 2 LAST CDS_LIB pure_quanta_power
J 0
(5450 450);
DISPLAY INVISIBLE (5450 450);
FORCEPROP 1 LAST PATH I83
J 0
(5525 450);
DISPLAY 0.872340 (5525 450);
PAINT AQUA (5525 450);
DISPLAY INVISIBLE (5525 450);
FORCEPROP 1 LAST HDL_POWER GND
J 1
(5475 375);
DISPLAY 0.872340 (5475 375);
PAINT GREEN (5475 375);
DISPLAY INVISIBLE (5475 375);
FORCEADD Q_CAP..1
(5450 775);
FORCEPROP 1 LAST LOCATION C3920
J 0
(5500 875);
DISPLAY 0.489362 (5500 875);
PAINT SKYBLUE (5500 875);
FORCEPROP 2 LAST $SEC 1
J 0
(5500 975);
DISPLAY 0.680851 (5500 975);
PAINT MONO (5500 975);
DISPLAY INVISIBLE (5500 975);
FORCEPROP 2 LAST CDS_SEC 1
J 0
(5500 975);
DISPLAY 1.021277 (5500 975);
DISPLAY INVISIBLE (5500 975);
FORCEPROP 1 LASTPIN (5450 875) $PN 1
J 0
(5460 855);
DISPLAY 0.489362 (5460 855);
FORCEPROP 1 LASTPIN (5450 675) $PN 2
J 0
(5460 655);
DISPLAY 0.489362 (5460 655);
FORCEPROP 1 LAST MATERIAL X6S
J 0
(5500 675);
DISPLAY 0.489362 (5500 675);
PAINT SKYBLUE (5500 675);
FORCEPROP 1 LAST TOLERANCE 20%
J 0
(5500 725);
DISPLAY 0.489362 (5500 725);
PAINT SKYBLUE (5500 725);
FORCEPROP 1 LAST VALUE 22UF
J 0
(5500 825);
DISPLAY 0.489362 (5500 825);
PAINT SKYBLUE (5500 825);
FORCEPROP 1 LAST PART_NUMBER CH622KMEB02
J 0
(5500 625);
DISPLAY 0.489362 (5500 625);
PAINT SKYBLUE (5500 625);
FORCEPROP 1 LAST VOLTAGE 4V
J 0
(5500 775);
DISPLAY 0.489362 (5500 775);
PAINT SKYBLUE (5500 775);
FORCEPROP 1 LAST PACK_TYPE C0402
J 0
(5500 575);
DISPLAY 0.489362 (5500 575);
PAINT SKYBLUE (5500 575);
FORCEPROP 2 LAST CDS_LIB pure_quanta
J 0
(5450 775);
PAINT MONO (5450 775);
DISPLAY INVISIBLE (5450 775);
FORCEPROP 1 LAST PATH I84
J 0
(5500 925);
DISPLAY 0.978723 (5500 925);
PAINT WHITE (5500 925);
DISPLAY INVISIBLE (5500 925);
FORCEADD Q_CAP..1
(5450 1375);
FORCEPROP 1 LAST LOCATION C2488
J 0
(5500 1475);
DISPLAY 0.489362 (5500 1475);
PAINT SKYBLUE (5500 1475);
FORCEPROP 2 LAST $SEC 1
J 0
(5500 1575);
DISPLAY 0.680851 (5500 1575);
PAINT MONO (5500 1575);
DISPLAY INVISIBLE (5500 1575);
FORCEPROP 2 LAST CDS_SEC 1
J 0
(5500 1575);
DISPLAY 1.021277 (5500 1575);
DISPLAY INVISIBLE (5500 1575);
FORCEPROP 1 LASTPIN (5450 1475) $PN 1
J 0
(5460 1455);
DISPLAY 0.489362 (5460 1455);
FORCEPROP 1 LASTPIN (5450 1275) $PN 2
J 0
(5460 1255);
DISPLAY 0.489362 (5460 1255);
FORCEPROP 1 LAST MATERIAL X6S
J 0
(5500 1275);
DISPLAY 0.489362 (5500 1275);
PAINT SKYBLUE (5500 1275);
FORCEPROP 1 LAST TOLERANCE 20%
J 0
(5500 1325);
DISPLAY 0.489362 (5500 1325);
PAINT SKYBLUE (5500 1325);
FORCEPROP 1 LAST VALUE 22UF
J 0
(5500 1425);
DISPLAY 0.489362 (5500 1425);
PAINT SKYBLUE (5500 1425);
FORCEPROP 1 LAST PART_NUMBER CH622KMEB02
J 0
(5500 1225);
DISPLAY 0.489362 (5500 1225);
PAINT SKYBLUE (5500 1225);
FORCEPROP 1 LAST VOLTAGE 4V
J 0
(5500 1375);
DISPLAY 0.489362 (5500 1375);
PAINT SKYBLUE (5500 1375);
FORCEPROP 1 LAST PACK_TYPE C0402
J 0
(5500 1175);
DISPLAY 0.489362 (5500 1175);
PAINT SKYBLUE (5500 1175);
FORCEPROP 2 LAST CDS_LIB pure_quanta
J 0
(5450 1375);
PAINT MONO (5450 1375);
DISPLAY INVISIBLE (5450 1375);
FORCEPROP 1 LAST PATH I85
J 0
(5500 1525);
DISPLAY 0.978723 (5500 1525);
PAINT WHITE (5500 1525);
DISPLAY INVISIBLE (5500 1525);
FORCEADD Q_CAP..1
(5900 1375);
FORCEPROP 1 LAST LOCATION C2492
J 0
(5950 1475);
DISPLAY 0.489362 (5950 1475);
PAINT SKYBLUE (5950 1475);
FORCEPROP 2 LAST $SEC 1
J 0
(5950 1575);
DISPLAY 0.680851 (5950 1575);
PAINT MONO (5950 1575);
DISPLAY INVISIBLE (5950 1575);
FORCEPROP 2 LAST CDS_SEC 1
J 0
(5950 1575);
DISPLAY 1.021277 (5950 1575);
DISPLAY INVISIBLE (5950 1575);
FORCEPROP 1 LASTPIN (5900 1475) $PN 1
J 0
(5910 1455);
DISPLAY 0.489362 (5910 1455);
FORCEPROP 1 LASTPIN (5900 1275) $PN 2
J 0
(5910 1255);
DISPLAY 0.489362 (5910 1255);
FORCEPROP 1 LAST MATERIAL X6S
J 0
(5950 1275);
DISPLAY 0.489362 (5950 1275);
PAINT SKYBLUE (5950 1275);
FORCEPROP 1 LAST TOLERANCE 20%
J 0
(5950 1325);
DISPLAY 0.489362 (5950 1325);
PAINT SKYBLUE (5950 1325);
FORCEPROP 1 LAST VALUE 22UF
J 0
(5950 1425);
DISPLAY 0.489362 (5950 1425);
PAINT SKYBLUE (5950 1425);
FORCEPROP 1 LAST PART_NUMBER CH622KMEB02
J 0
(5950 1225);
DISPLAY 0.489362 (5950 1225);
PAINT SKYBLUE (5950 1225);
FORCEPROP 1 LAST VOLTAGE 4V
J 0
(5950 1375);
DISPLAY 0.489362 (5950 1375);
PAINT SKYBLUE (5950 1375);
FORCEPROP 1 LAST PACK_TYPE C0402
J 0
(5950 1175);
DISPLAY 0.489362 (5950 1175);
PAINT SKYBLUE (5950 1175);
FORCEPROP 2 LAST CDS_LIB pure_quanta
J 0
(5900 1375);
PAINT MONO (5900 1375);
DISPLAY INVISIBLE (5900 1375);
FORCEPROP 1 LAST PATH I86
J 0
(5950 1525);
DISPLAY 0.978723 (5950 1525);
PAINT WHITE (5950 1525);
DISPLAY INVISIBLE (5950 1525);
FORCEADD UNIVERSAL_GND..1
(4400 2100);
FORCEPROP 3 LASTPIN (4400 2150) SIG_NAME GND\g
J 0
(4410 2160);
DISPLAY 0.659574 (4410 2160);
PAINT MONO (4410 2160);
DISPLAY INVISIBLE (4410 2160);
FORCEPROP 2 LAST CDS_LIB pure_quanta_power
J 0
(4400 2100);
PAINT MONO (4400 2100);
DISPLAY INVISIBLE (4400 2100);
FORCEPROP 1 LAST PATH I87
J 0
(4475 2100);
DISPLAY 0.872340 (4475 2100);
PAINT AQUA (4475 2100);
DISPLAY INVISIBLE (4475 2100);
FORCEPROP 1 LAST HDL_POWER GND
J 1
(4425 2025);
DISPLAY 0.872340 (4425 2025);
PAINT GREEN (4425 2025);
DISPLAY INVISIBLE (4425 2025);
FORCEADD Q_CAP..1
(4400 2475);
FORCEPROP 1 LAST LOCATION C2475
J 0
(4450 2575);
DISPLAY 0.489362 (4450 2575);
PAINT SKYBLUE (4450 2575);
FORCEPROP 2 LAST $SEC 1
J 0
(4450 2675);
DISPLAY 0.680851 (4450 2675);
PAINT MONO (4450 2675);
DISPLAY INVISIBLE (4450 2675);
FORCEPROP 2 LAST CDS_SEC 1
J 0
(4450 2675);
DISPLAY 1.021277 (4450 2675);
DISPLAY INVISIBLE (4450 2675);
FORCEPROP 1 LASTPIN (4400 2575) $PN 1
J 0
(4410 2555);
DISPLAY 0.489362 (4410 2555);
FORCEPROP 1 LASTPIN (4400 2375) $PN 2
J 0
(4410 2355);
DISPLAY 0.489362 (4410 2355);
FORCEPROP 1 LAST MATERIAL X6S
J 0
(4450 2375);
DISPLAY 0.489362 (4450 2375);
PAINT SKYBLUE (4450 2375);
FORCEPROP 1 LAST TOLERANCE 20%
J 0
(4450 2425);
DISPLAY 0.489362 (4450 2425);
PAINT SKYBLUE (4450 2425);
FORCEPROP 1 LAST VALUE 22UF
J 0
(4450 2525);
DISPLAY 0.489362 (4450 2525);
PAINT SKYBLUE (4450 2525);
FORCEPROP 1 LAST PART_NUMBER CH622KMEB02
J 0
(4450 2325);
DISPLAY 0.489362 (4450 2325);
PAINT SKYBLUE (4450 2325);
FORCEPROP 1 LAST VOLTAGE 4V
J 0
(4450 2475);
DISPLAY 0.489362 (4450 2475);
PAINT SKYBLUE (4450 2475);
FORCEPROP 1 LAST PACK_TYPE C0402
J 0
(4450 2275);
DISPLAY 0.489362 (4450 2275);
PAINT SKYBLUE (4450 2275);
FORCEPROP 2 LAST CDS_LIB pure_quanta
J 0
(4400 2475);
PAINT MONO (4400 2475);
DISPLAY INVISIBLE (4400 2475);
FORCEPROP 1 LAST PATH I88
J 0
(4450 2625);
DISPLAY 0.978723 (4450 2625);
PAINT WHITE (4450 2625);
DISPLAY INVISIBLE (4450 2625);
FORCEADD UNIVERSAL_GND..1
(4400 2775);
FORCEPROP 3 LASTPIN (4400 2825) SIG_NAME GND\g
J 0
(4410 2835);
DISPLAY 0.659574 (4410 2835);
PAINT MONO (4410 2835);
DISPLAY INVISIBLE (4410 2835);
FORCEPROP 2 LAST CDS_LIB pure_quanta_power
J 0
(4400 2775);
PAINT MONO (4400 2775);
DISPLAY INVISIBLE (4400 2775);
FORCEPROP 1 LAST PATH I89
J 0
(4475 2775);
DISPLAY 0.872340 (4475 2775);
PAINT AQUA (4475 2775);
DISPLAY INVISIBLE (4475 2775);
FORCEPROP 1 LAST HDL_POWER GND
J 1
(4425 2700);
DISPLAY 0.872340 (4425 2700);
PAINT GREEN (4425 2700);
DISPLAY INVISIBLE (4425 2700);
FORCEADD Q_CAP..1
(1750 1800);
FORCEPROP 1 LAST LOCATION C2434
J 0
(1800 1900);
DISPLAY 0.489362 (1800 1900);
PAINT SKYBLUE (1800 1900);
FORCEPROP 2 LAST $SEC 1
J 0
(1800 2000);
DISPLAY 0.680851 (1800 2000);
PAINT MONO (1800 2000);
DISPLAY INVISIBLE (1800 2000);
FORCEPROP 2 LAST CDS_SEC 1
J 0
(1800 2000);
DISPLAY 1.021277 (1800 2000);
DISPLAY INVISIBLE (1800 2000);
FORCEPROP 1 LASTPIN (1750 1900) $PN 1
J 0
(1760 1880);
DISPLAY 0.489362 (1760 1880);
FORCEPROP 1 LASTPIN (1750 1700) $PN 2
J 0
(1760 1680);
DISPLAY 0.489362 (1760 1680);
FORCEPROP 1 LAST MATERIAL X6S
J 0
(1800 1700);
DISPLAY 0.489362 (1800 1700);
PAINT SKYBLUE (1800 1700);
FORCEPROP 1 LAST TOLERANCE 20%
J 0
(1800 1750);
DISPLAY 0.489362 (1800 1750);
PAINT SKYBLUE (1800 1750);
FORCEPROP 1 LAST VALUE 22UF
J 0
(1800 1850);
DISPLAY 0.489362 (1800 1850);
PAINT SKYBLUE (1800 1850);
FORCEPROP 1 LAST PART_NUMBER CH622KMEB02
J 0
(1800 1650);
DISPLAY 0.489362 (1800 1650);
PAINT SKYBLUE (1800 1650);
FORCEPROP 1 LAST VOLTAGE 4V
J 0
(1800 1800);
DISPLAY 0.489362 (1800 1800);
PAINT SKYBLUE (1800 1800);
FORCEPROP 1 LAST PACK_TYPE C0402
J 0
(1800 1600);
DISPLAY 0.489362 (1800 1600);
PAINT SKYBLUE (1800 1600);
FORCEPROP 2 LAST CDS_LIB pure_quanta
J 0
(1750 1800);
PAINT MONO (1750 1800);
DISPLAY INVISIBLE (1750 1800);
FORCEPROP 1 LAST PATH I9
J 0
(1800 1950);
DISPLAY 0.978723 (1800 1950);
PAINT WHITE (1800 1950);
DISPLAY INVISIBLE (1800 1950);
FORCEADD Q_CAP..1
(5000 2025);
FORCEPROP 1 LAST LOCATION C2482
J 0
(5050 2125);
DISPLAY 0.489362 (5050 2125);
PAINT SKYBLUE (5050 2125);
FORCEPROP 2 LAST $SEC 1
J 0
(5050 2225);
DISPLAY 0.680851 (5050 2225);
PAINT MONO (5050 2225);
DISPLAY INVISIBLE (5050 2225);
FORCEPROP 2 LAST CDS_SEC 1
J 0
(5050 2225);
DISPLAY 1.021277 (5050 2225);
DISPLAY INVISIBLE (5050 2225);
FORCEPROP 1 LASTPIN (5000 2125) $PN 1
J 0
(5010 2105);
DISPLAY 0.489362 (5010 2105);
FORCEPROP 1 LASTPIN (5000 1925) $PN 2
J 0
(5010 1905);
DISPLAY 0.489362 (5010 1905);
FORCEPROP 1 LAST MATERIAL X6S
J 0
(5050 1925);
DISPLAY 0.489362 (5050 1925);
PAINT SKYBLUE (5050 1925);
FORCEPROP 1 LAST TOLERANCE 20%
J 0
(5050 1975);
DISPLAY 0.489362 (5050 1975);
PAINT SKYBLUE (5050 1975);
FORCEPROP 1 LAST VALUE 22UF
J 0
(5050 2075);
DISPLAY 0.489362 (5050 2075);
PAINT SKYBLUE (5050 2075);
FORCEPROP 1 LAST PART_NUMBER CH622KMEB02
J 0
(5050 1875);
DISPLAY 0.489362 (5050 1875);
PAINT SKYBLUE (5050 1875);
FORCEPROP 1 LAST VOLTAGE 4V
J 0
(5050 2025);
DISPLAY 0.489362 (5050 2025);
PAINT SKYBLUE (5050 2025);
FORCEPROP 1 LAST PACK_TYPE C0402
J 0
(5050 1825);
DISPLAY 0.489362 (5050 1825);
PAINT SKYBLUE (5050 1825);
FORCEPROP 2 LAST CDS_LIB pure_quanta
J 0
(5000 2025);
PAINT MONO (5000 2025);
DISPLAY INVISIBLE (5000 2025);
FORCEPROP 1 LAST PATH I90
J 0
(5050 2175);
DISPLAY 0.978723 (5050 2175);
PAINT WHITE (5050 2175);
DISPLAY INVISIBLE (5050 2175);
FORCEADD UNIVERSAL_POWER..1
(5000 2300);
FORCEPROP 3 LASTPIN (5000 2250) SIG_NAME PVDD11_S3_P1\g
J 0
(5010 2260);
DISPLAY 0.659574 (5010 2260);
PAINT MONO (5010 2260);
DISPLAY INVISIBLE (5010 2260);
FORCEPROP 1 LAST HDL_POWER PVDD11_S3_P1
J 1
(5000 2350);
DISPLAY 0.489362 (5000 2350);
PAINT GREEN (5000 2350);
FORCEPROP 2 LAST CDS_LIB pure_quanta_power
J 0
(5000 2300);
DISPLAY INVISIBLE (5000 2300);
FORCEPROP 1 LAST PATH I91
J 0
(5050 2325);
DISPLAY 0.872340 (5050 2325);
PAINT AQUA (5050 2325);
DISPLAY INVISIBLE (5050 2325);
FORCEADD Q_CAP..1
(5000 2650);
FORCEPROP 1 LAST LOCATION C2481
J 0
(5050 2750);
DISPLAY 0.489362 (5050 2750);
PAINT SKYBLUE (5050 2750);
FORCEPROP 2 LAST $SEC 1
J 0
(5050 2850);
DISPLAY 0.680851 (5050 2850);
PAINT MONO (5050 2850);
DISPLAY INVISIBLE (5050 2850);
FORCEPROP 2 LAST CDS_SEC 1
J 0
(5050 2850);
DISPLAY 1.021277 (5050 2850);
DISPLAY INVISIBLE (5050 2850);
FORCEPROP 1 LASTPIN (5000 2750) $PN 1
J 0
(5010 2730);
DISPLAY 0.489362 (5010 2730);
FORCEPROP 1 LASTPIN (5000 2550) $PN 2
J 0
(5010 2530);
DISPLAY 0.489362 (5010 2530);
FORCEPROP 1 LAST MATERIAL X6S
J 0
(5050 2550);
DISPLAY 0.489362 (5050 2550);
PAINT SKYBLUE (5050 2550);
FORCEPROP 1 LAST TOLERANCE 20%
J 0
(5050 2600);
DISPLAY 0.489362 (5050 2600);
PAINT SKYBLUE (5050 2600);
FORCEPROP 1 LAST VALUE 22UF
J 0
(5050 2700);
DISPLAY 0.489362 (5050 2700);
PAINT SKYBLUE (5050 2700);
FORCEPROP 1 LAST PART_NUMBER CH622KMEB02
J 0
(5050 2500);
DISPLAY 0.489362 (5050 2500);
PAINT SKYBLUE (5050 2500);
FORCEPROP 1 LAST VOLTAGE 4V
J 0
(5050 2650);
DISPLAY 0.489362 (5050 2650);
PAINT SKYBLUE (5050 2650);
FORCEPROP 1 LAST PACK_TYPE C0402
J 0
(5050 2450);
DISPLAY 0.489362 (5050 2450);
PAINT SKYBLUE (5050 2450);
FORCEPROP 2 LAST CDS_LIB pure_quanta
J 0
(5000 2650);
PAINT MONO (5000 2650);
DISPLAY INVISIBLE (5000 2650);
FORCEPROP 1 LAST PATH I92
J 0
(5050 2800);
DISPLAY 0.978723 (5050 2800);
PAINT WHITE (5050 2800);
DISPLAY INVISIBLE (5050 2800);
FORCEADD UNIVERSAL_POWER..1
(5000 2925);
FORCEPROP 3 LASTPIN (5000 2875) SIG_NAME PVDD11_S3_P1\g
J 0
(5010 2885);
DISPLAY 0.659574 (5010 2885);
PAINT MONO (5010 2885);
DISPLAY INVISIBLE (5010 2885);
FORCEPROP 1 LAST HDL_POWER PVDD11_S3_P1
J 1
(5000 2975);
DISPLAY 0.489362 (5000 2975);
PAINT GREEN (5000 2975);
FORCEPROP 2 LAST CDS_LIB pure_quanta_power
J 0
(5000 2925);
DISPLAY INVISIBLE (5000 2925);
FORCEPROP 1 LAST PATH I93
J 0
(5050 2950);
DISPLAY 0.872340 (5050 2950);
PAINT AQUA (5050 2950);
DISPLAY INVISIBLE (5050 2950);
FORCEADD Q_CAP..1
(4400 3150);
FORCEPROP 1 LAST LOCATION C2474
J 0
(4450 3250);
DISPLAY 0.489362 (4450 3250);
PAINT SKYBLUE (4450 3250);
FORCEPROP 2 LAST $SEC 1
J 0
(4450 3350);
DISPLAY 0.680851 (4450 3350);
PAINT MONO (4450 3350);
DISPLAY INVISIBLE (4450 3350);
FORCEPROP 2 LAST CDS_SEC 1
J 0
(4450 3350);
DISPLAY 1.021277 (4450 3350);
DISPLAY INVISIBLE (4450 3350);
FORCEPROP 1 LASTPIN (4400 3250) $PN 1
J 0
(4410 3230);
DISPLAY 0.489362 (4410 3230);
FORCEPROP 1 LASTPIN (4400 3050) $PN 2
J 0
(4410 3030);
DISPLAY 0.489362 (4410 3030);
FORCEPROP 1 LAST MATERIAL X6S
J 0
(4450 3050);
DISPLAY 0.489362 (4450 3050);
PAINT SKYBLUE (4450 3050);
FORCEPROP 1 LAST TOLERANCE 20%
J 0
(4450 3100);
DISPLAY 0.489362 (4450 3100);
PAINT SKYBLUE (4450 3100);
FORCEPROP 1 LAST VALUE 22UF
J 0
(4450 3200);
DISPLAY 0.489362 (4450 3200);
PAINT SKYBLUE (4450 3200);
FORCEPROP 1 LAST PART_NUMBER CH622KMEB02
J 0
(4450 3000);
DISPLAY 0.489362 (4450 3000);
PAINT SKYBLUE (4450 3000);
FORCEPROP 1 LAST VOLTAGE 4V
J 0
(4450 3150);
DISPLAY 0.489362 (4450 3150);
PAINT SKYBLUE (4450 3150);
FORCEPROP 1 LAST PACK_TYPE C0402
J 0
(4450 2950);
DISPLAY 0.489362 (4450 2950);
PAINT SKYBLUE (4450 2950);
FORCEPROP 2 LAST CDS_LIB pure_quanta
J 0
(4400 3150);
PAINT MONO (4400 3150);
DISPLAY INVISIBLE (4400 3150);
FORCEPROP 1 LAST PATH I94
J 0
(4450 3300);
DISPLAY 0.978723 (4450 3300);
PAINT WHITE (4450 3300);
DISPLAY INVISIBLE (4450 3300);
FORCEADD UNIVERSAL_GND..1
(4400 3475);
FORCEPROP 3 LASTPIN (4400 3525) SIG_NAME GND\g
J 0
(4410 3535);
DISPLAY 0.659574 (4410 3535);
PAINT MONO (4410 3535);
DISPLAY INVISIBLE (4410 3535);
FORCEPROP 2 LAST CDS_LIB pure_quanta_power
J 0
(4400 3475);
PAINT MONO (4400 3475);
DISPLAY INVISIBLE (4400 3475);
FORCEPROP 1 LAST PATH I95
J 0
(4475 3475);
DISPLAY 0.872340 (4475 3475);
PAINT AQUA (4475 3475);
DISPLAY INVISIBLE (4475 3475);
FORCEPROP 1 LAST HDL_POWER GND
J 1
(4425 3400);
DISPLAY 0.872340 (4425 3400);
PAINT GREEN (4425 3400);
DISPLAY INVISIBLE (4425 3400);
FORCEADD Q_CAP..1
(4400 3850);
FORCEPROP 1 LAST LOCATION C2473
J 0
(4450 3950);
DISPLAY 0.489362 (4450 3950);
PAINT SKYBLUE (4450 3950);
FORCEPROP 2 LAST $SEC 1
J 0
(4450 4050);
DISPLAY 0.680851 (4450 4050);
PAINT MONO (4450 4050);
DISPLAY INVISIBLE (4450 4050);
FORCEPROP 2 LAST CDS_SEC 1
J 0
(4450 4050);
DISPLAY 1.021277 (4450 4050);
DISPLAY INVISIBLE (4450 4050);
FORCEPROP 1 LASTPIN (4400 3950) $PN 1
J 0
(4410 3930);
DISPLAY 0.489362 (4410 3930);
FORCEPROP 1 LASTPIN (4400 3750) $PN 2
J 0
(4410 3730);
DISPLAY 0.489362 (4410 3730);
FORCEPROP 1 LAST MATERIAL X6S
J 0
(4450 3750);
DISPLAY 0.489362 (4450 3750);
PAINT SKYBLUE (4450 3750);
FORCEPROP 1 LAST TOLERANCE 20%
J 0
(4450 3800);
DISPLAY 0.489362 (4450 3800);
PAINT SKYBLUE (4450 3800);
FORCEPROP 1 LAST VALUE 22UF
J 0
(4450 3900);
DISPLAY 0.489362 (4450 3900);
PAINT SKYBLUE (4450 3900);
FORCEPROP 1 LAST PART_NUMBER CH622KMEB02
J 0
(4450 3700);
DISPLAY 0.489362 (4450 3700);
PAINT SKYBLUE (4450 3700);
FORCEPROP 1 LAST VOLTAGE 4V
J 0
(4450 3850);
DISPLAY 0.489362 (4450 3850);
PAINT SKYBLUE (4450 3850);
FORCEPROP 1 LAST PACK_TYPE C0402
J 0
(4450 3650);
DISPLAY 0.489362 (4450 3650);
PAINT SKYBLUE (4450 3650);
FORCEPROP 2 LAST CDS_LIB pure_quanta
J 0
(4400 3850);
PAINT MONO (4400 3850);
DISPLAY INVISIBLE (4400 3850);
FORCEPROP 1 LAST PATH I96
J 0
(4450 4000);
DISPLAY 0.978723 (4450 4000);
PAINT WHITE (4450 4000);
DISPLAY INVISIBLE (4450 4000);
FORCEADD Q_CAP..1
(5000 3325);
FORCEPROP 1 LAST LOCATION C2480
J 0
(5050 3425);
DISPLAY 0.489362 (5050 3425);
PAINT SKYBLUE (5050 3425);
FORCEPROP 2 LAST $SEC 1
J 0
(5050 3525);
DISPLAY 0.680851 (5050 3525);
PAINT MONO (5050 3525);
DISPLAY INVISIBLE (5050 3525);
FORCEPROP 2 LAST CDS_SEC 1
J 0
(5050 3525);
DISPLAY 1.021277 (5050 3525);
DISPLAY INVISIBLE (5050 3525);
FORCEPROP 1 LASTPIN (5000 3425) $PN 1
J 0
(5010 3405);
DISPLAY 0.489362 (5010 3405);
FORCEPROP 1 LASTPIN (5000 3225) $PN 2
J 0
(5010 3205);
DISPLAY 0.489362 (5010 3205);
FORCEPROP 1 LAST MATERIAL X6S
J 0
(5050 3225);
DISPLAY 0.489362 (5050 3225);
PAINT SKYBLUE (5050 3225);
FORCEPROP 1 LAST TOLERANCE 20%
J 0
(5050 3275);
DISPLAY 0.489362 (5050 3275);
PAINT SKYBLUE (5050 3275);
FORCEPROP 1 LAST VALUE 22UF
J 0
(5050 3375);
DISPLAY 0.489362 (5050 3375);
PAINT SKYBLUE (5050 3375);
FORCEPROP 1 LAST PART_NUMBER CH622KMEB02
J 0
(5050 3175);
DISPLAY 0.489362 (5050 3175);
PAINT SKYBLUE (5050 3175);
FORCEPROP 1 LAST VOLTAGE 4V
J 0
(5050 3325);
DISPLAY 0.489362 (5050 3325);
PAINT SKYBLUE (5050 3325);
FORCEPROP 1 LAST PACK_TYPE C0402
J 0
(5050 3125);
DISPLAY 0.489362 (5050 3125);
PAINT SKYBLUE (5050 3125);
FORCEPROP 2 LAST CDS_LIB pure_quanta
J 0
(5000 3325);
PAINT MONO (5000 3325);
DISPLAY INVISIBLE (5000 3325);
FORCEPROP 1 LAST PATH I97
J 0
(5050 3475);
DISPLAY 0.978723 (5050 3475);
PAINT WHITE (5050 3475);
DISPLAY INVISIBLE (5050 3475);
FORCEADD UNIVERSAL_POWER..1
(5000 3600);
FORCEPROP 3 LASTPIN (5000 3550) SIG_NAME PVDD11_S3_P1\g
J 0
(5010 3560);
DISPLAY 0.659574 (5010 3560);
PAINT MONO (5010 3560);
DISPLAY INVISIBLE (5010 3560);
FORCEPROP 1 LAST HDL_POWER PVDD11_S3_P1
J 1
(5000 3650);
DISPLAY 0.489362 (5000 3650);
PAINT GREEN (5000 3650);
FORCEPROP 2 LAST CDS_LIB pure_quanta_power
J 0
(5000 3600);
DISPLAY INVISIBLE (5000 3600);
FORCEPROP 1 LAST PATH I98
J 0
(5050 3625);
DISPLAY 0.872340 (5050 3625);
PAINT AQUA (5050 3625);
DISPLAY INVISIBLE (5050 3625);
FORCEADD Q_CAP..1
(5450 2025);
FORCEPROP 1 LAST LOCATION C2487
J 0
(5500 2125);
DISPLAY 0.489362 (5500 2125);
PAINT SKYBLUE (5500 2125);
FORCEPROP 2 LAST $SEC 1
J 0
(5500 2225);
DISPLAY 0.680851 (5500 2225);
PAINT MONO (5500 2225);
DISPLAY INVISIBLE (5500 2225);
FORCEPROP 2 LAST CDS_SEC 1
J 0
(5500 2225);
DISPLAY 1.021277 (5500 2225);
DISPLAY INVISIBLE (5500 2225);
FORCEPROP 1 LASTPIN (5450 2125) $PN 1
J 0
(5460 2105);
DISPLAY 0.489362 (5460 2105);
FORCEPROP 1 LASTPIN (5450 1925) $PN 2
J 0
(5460 1905);
DISPLAY 0.489362 (5460 1905);
FORCEPROP 1 LAST MATERIAL X6S
J 0
(5500 1925);
DISPLAY 0.489362 (5500 1925);
PAINT SKYBLUE (5500 1925);
FORCEPROP 1 LAST TOLERANCE 20%
J 0
(5500 1975);
DISPLAY 0.489362 (5500 1975);
PAINT SKYBLUE (5500 1975);
FORCEPROP 1 LAST VALUE 22UF
J 0
(5500 2075);
DISPLAY 0.489362 (5500 2075);
PAINT SKYBLUE (5500 2075);
FORCEPROP 1 LAST PART_NUMBER CH622KMEB02
J 0
(5500 1875);
DISPLAY 0.489362 (5500 1875);
PAINT SKYBLUE (5500 1875);
FORCEPROP 1 LAST VOLTAGE 4V
J 0
(5500 2025);
DISPLAY 0.489362 (5500 2025);
PAINT SKYBLUE (5500 2025);
FORCEPROP 1 LAST PACK_TYPE C0402
J 0
(5500 1825);
DISPLAY 0.489362 (5500 1825);
PAINT SKYBLUE (5500 1825);
FORCEPROP 2 LAST CDS_LIB pure_quanta
J 0
(5450 2025);
PAINT MONO (5450 2025);
DISPLAY INVISIBLE (5450 2025);
FORCEPROP 1 LAST PATH I99
J 0
(5500 2175);
DISPLAY 0.978723 (5500 2175);
PAINT WHITE (5500 2175);
DISPLAY INVISIBLE (5500 2175);
FORCEADD QUANTA_TITLE_BLOCK_C..1
(9425 200);
FORCEPROP 0 LAST CDS_CON_LAST_MODIFIED Fri Mar 11 14:52:47 2022
J 0
(7540 215);
DISPLAY INVISIBLE (7540 215);
FORCEPROP 1 LAST CUSTOM_TXT_CDS <CON_LAST_MODIFIED>
J 0
(7540 215);
DISPLAY 0.978723 (7540 215);
FORCEPROP 2 LAST CUSTOM_TXT_CDS <XR_PAGE_TITLE>
J 0
(1535 5450);
DISPLAY 0.638298 (1535 5450);
PAINT PINK (1535 5450);
DISPLAY INVISIBLE (1535 5450);
FORCEPROP 1 LAST CUSTOM_TXT_CDS <NAME_2>
J 0
(6250 250);
FORCEPROP 1 LAST CUSTOM_TXT_CDS <NAME_1>
J 0
(6250 375);
FORCEPROP 1 LAST CUSTOM_TXT_CDS <Q_NUMBER>
J 0
(8022 303);
DISPLAY 1.212766 (8022 303);
FORCEPROP 1 LAST CUSTOM_TXT_CDS <Q_PROJ>
J 0
(7043 302);
DISPLAY 1.212766 (7043 302);
FORCEPROP 1 LAST CUSTOM_TXT_CDS <Q_REV>
J 0
(9241 303);
DISPLAY 1.212766 (9241 303);
FORCEPROP 1 LAST CUSTOM_TXT_CDS <CON_PAGE_NUM> OF <CON_TOTAL_PAGES>
J 0
(8979 218);
DISPLAY 0.978723 (8979 218);
FORCEPROP 1 LAST Q_DEPT BU9
J 1
(5662 249);
DISPLAY 1.957447 (5662 249);
PAINT GREEN (5662 249);
FORCEPROP 1 LAST Q_TITLE CPU1 CAVITY BOT DECOUPLING CAPS 2/3
J 0
(59 226);
DISPLAY 2.446809 (59 226);
PAINT GREEN (59 226);
FORCEPROP 2 LAST PAGE_BORDER TRUE
J 0
(1535 5450);
DISPLAY 0.638298 (1535 5450);
PAINT PINK (1535 5450);
DISPLAY INVISIBLE (1535 5450);
FORCEPROP 2 LAST CDS_LIB pure_quanta
J 0
(9425 200);
DISPLAY INVISIBLE (9425 200);
FORCEPROP 1 LAST CDS_LMAN_SYM_OUTLINE -9475,6775,100,-125
J 0
(9425 200);
DISPLAY 0.468085 (9425 200);
PAINT GREEN (9425 200);
DISPLAY INVISIBLE (9425 200);
FORCEPROP 1 LAST COMMENT_BODY TRUE
J 0
(9437 187);
DISPLAY 0.978723 (9437 187);
PAINT GREEN (9437 187);
DISPLAY INVISIBLE (9437 187);
FORCEPROP 2 LAST CDS_XR_PAGE_TITLE CR-73 : @T6G_MB_LIB.T6G(SCH_1):PAGE73
J 0
(1535 5450);
DISPLAY 0.638298 (1535 5450);
PAINT PINK (1535 5450);
DISPLAY INVISIBLE (1535 5450);
WIRE 16 -1 (850 850)(400 850);
WIRE 16 -1 (1300 850)(850 850);
WIRE 16 -1 (850 850)(850 975);
WIRE 16 -1 (400 850)(400 975);
WIRE 16 -1 (1750 850)(1300 850);
WIRE 16 -1 (1300 850)(1300 975);
WIRE 16 -1 (2200 850)(1750 850);
WIRE 16 -1 (1750 850)(1750 975);
WIRE 16 -1 (2650 850)(2200 850);
WIRE 16 -1 (2200 850)(2200 975);
WIRE 16 -1 (3100 850)(2650 850);
WIRE 16 -1 (2650 850)(2650 975);
WIRE 16 -1 (3100 750)(3100 850);
WIRE 16 -1 (3100 850)(3100 975);
WIRE 16 -1 (4400 1900)(4400 1975);
WIRE 16 -1 (4400 1975)(4000 1975);
WIRE 16 -1 (4000 1975)(4000 1900);
WIRE 16 -1 (4000 1975)(3550 1975);
WIRE 16 -1 (3550 1900)(3550 1975);
WIRE 16 -1 (3550 1975)(3100 1975);
WIRE 16 -1 (3100 1900)(3100 1975);
WIRE 16 -1 (3100 1975)(2650 1975);
WIRE 16 -1 (2650 1975)(2650 1900);
WIRE 16 -1 (2650 1975)(2200 1975);
WIRE 16 -1 (2200 1900)(2200 1975);
WIRE 16 -1 (2200 1975)(1750 1975);
WIRE 16 -1 (1750 1900)(1750 1975);
WIRE 16 -1 (1750 1975)(1300 1975);
WIRE 16 -1 (1300 1975)(1300 1900);
WIRE 16 -1 (1300 1975)(850 1975);
WIRE 16 -1 (850 1975)(400 1975);
WIRE 16 -1 (850 1900)(850 1975);
WIRE 16 -1 (400 1975)(400 2025);
WIRE 16 -1 (400 1975)(400 1900);
WIRE 16 -1 (850 1575)(400 1575);
WIRE 16 -1 (1300 1575)(850 1575);
WIRE 16 -1 (850 1575)(850 1700);
WIRE 16 -1 (400 1575)(400 1700);
WIRE 16 -1 (1750 1575)(1300 1575);
WIRE 16 -1 (1300 1575)(1300 1700);
WIRE 16 -1 (2200 1575)(1750 1575);
WIRE 16 -1 (1750 1575)(1750 1700);
WIRE 16 -1 (2650 1575)(2200 1575);
WIRE 16 -1 (2200 1575)(2200 1700);
WIRE 16 -1 (3100 1575)(2650 1575);
WIRE 16 -1 (2650 1575)(2650 1700);
WIRE 16 -1 (3550 1575)(3100 1575);
WIRE 16 -1 (3100 1575)(3100 1700);
WIRE 16 -1 (4000 1575)(3550 1575);
WIRE 16 -1 (3550 1575)(3550 1700);
WIRE 16 -1 (4400 1575)(4000 1575);
WIRE 16 -1 (4000 1575)(4000 1700);
WIRE 16 -1 (4400 1575)(4400 1700);
WIRE 16 -1 (4400 1475)(4400 1575);
WIRE 16 -1 (850 1250)(400 1250);
WIRE 16 -1 (1300 1250)(850 1250);
WIRE 16 -1 (850 1175)(850 1250);
WIRE 16 -1 (400 1250)(400 1300);
WIRE 16 -1 (400 1250)(400 1175);
WIRE 16 -1 (1750 1250)(1300 1250);
WIRE 16 -1 (1300 1250)(1300 1175);
WIRE 16 -1 (2200 1250)(1750 1250);
WIRE 16 -1 (1750 1175)(1750 1250);
WIRE 16 -1 (2650 1250)(2200 1250);
WIRE 16 -1 (2200 1175)(2200 1250);
WIRE 16 -1 (3100 1250)(2650 1250);
WIRE 16 -1 (2650 1250)(2650 1175);
WIRE 16 -1 (3100 1175)(3100 1250);
WIRE 16 -1 (850 2925)(400 2925);
WIRE 16 -1 (1300 2925)(850 2925);
WIRE 16 -1 (850 2925)(850 3050);
WIRE 16 -1 (400 2925)(400 3050);
WIRE 16 -1 (1750 2925)(1300 2925);
WIRE 16 -1 (1300 2925)(1300 3050);
WIRE 16 -1 (2200 2925)(1750 2925);
WIRE 16 -1 (1750 2925)(1750 3050);
WIRE 16 -1 (2650 2925)(2200 2925);
WIRE 16 -1 (2200 2925)(2200 3050);
WIRE 16 -1 (3100 2925)(2650 2925);
WIRE 16 -1 (2650 2925)(2650 3050);
WIRE 16 -1 (3550 2925)(3100 2925);
WIRE 16 -1 (3100 2925)(3100 3050);
WIRE 16 -1 (4000 2925)(3550 2925);
WIRE 16 -1 (3550 2925)(3550 3050);
WIRE 16 -1 (4400 2925)(4000 2925);
WIRE 16 -1 (4000 2925)(4000 3050);
WIRE 16 -1 (4400 2825)(4400 2925);
WIRE 16 -1 (4400 2925)(4400 3050);
WIRE 16 -1 (4400 2575)(4400 2650);
WIRE 16 -1 (4400 2650)(4000 2650);
WIRE 16 -1 (4000 2650)(4000 2575);
WIRE 16 -1 (4000 2650)(3550 2650);
WIRE 16 -1 (3550 2575)(3550 2650);
WIRE 16 -1 (3550 2650)(3100 2650);
WIRE 16 -1 (3100 2575)(3100 2650);
WIRE 16 -1 (3100 2650)(2650 2650);
WIRE 16 -1 (2650 2650)(2650 2575);
WIRE 16 -1 (2650 2650)(2200 2650);
WIRE 16 -1 (2200 2575)(2200 2650);
WIRE 16 -1 (2200 2650)(1750 2650);
WIRE 16 -1 (1750 2575)(1750 2650);
WIRE 16 -1 (1750 2650)(1300 2650);
WIRE 16 -1 (1300 2650)(1300 2575);
WIRE 16 -1 (1300 2650)(850 2650);
WIRE 16 -1 (850 2650)(400 2650);
WIRE 16 -1 (850 2575)(850 2650);
WIRE 16 -1 (400 2650)(400 2700);
WIRE 16 -1 (400 2650)(400 2575);
WIRE 16 -1 (850 2250)(400 2250);
WIRE 16 -1 (1300 2250)(850 2250);
WIRE 16 -1 (850 2250)(850 2375);
WIRE 16 -1 (400 2250)(400 2375);
WIRE 16 -1 (1750 2250)(1300 2250);
WIRE 16 -1 (1300 2250)(1300 2375);
WIRE 16 -1 (2200 2250)(1750 2250);
WIRE 16 -1 (1750 2250)(1750 2375);
WIRE 16 -1 (2650 2250)(2200 2250);
WIRE 16 -1 (2200 2250)(2200 2375);
WIRE 16 -1 (3100 2250)(2650 2250);
WIRE 16 -1 (2650 2250)(2650 2375);
WIRE 16 -1 (3550 2250)(3100 2250);
WIRE 16 -1 (3100 2250)(3100 2375);
WIRE 16 -1 (4000 2250)(3550 2250);
WIRE 16 -1 (3550 2250)(3550 2375);
WIRE 16 -1 (4400 2250)(4000 2250);
WIRE 16 -1 (4000 2250)(4000 2375);
WIRE 16 -1 (4400 2250)(4400 2375);
WIRE 16 -1 (4400 2150)(4400 2250);
WIRE 16 -1 (4400 3950)(4400 4025);
WIRE 16 -1 (4400 4025)(4000 4025);
WIRE 16 -1 (4000 4025)(4000 3950);
WIRE 16 -1 (4000 4025)(3550 4025);
WIRE 16 -1 (3550 3950)(3550 4025);
WIRE 16 -1 (3550 4025)(3100 4025);
WIRE 16 -1 (3100 3950)(3100 4025);
WIRE 16 -1 (3100 4025)(2650 4025);
WIRE 16 -1 (2650 4025)(2650 3950);
WIRE 16 -1 (2650 4025)(2200 4025);
WIRE 16 -1 (2200 3950)(2200 4025);
WIRE 16 -1 (2200 4025)(1750 4025);
WIRE 16 -1 (1750 3950)(1750 4025);
WIRE 16 -1 (1750 4025)(1300 4025);
WIRE 16 -1 (1300 4025)(1300 3950);
WIRE 16 -1 (1300 4025)(850 4025);
WIRE 16 -1 (850 4025)(400 4025);
WIRE 16 -1 (850 3950)(850 4025);
WIRE 16 -1 (400 4025)(400 4075);
WIRE 16 -1 (400 4025)(400 3950);
WIRE 16 -1 (850 3625)(400 3625);
WIRE 16 -1 (1300 3625)(850 3625);
WIRE 16 -1 (850 3625)(850 3750);
WIRE 16 -1 (400 3625)(400 3750);
WIRE 16 -1 (1750 3625)(1300 3625);
WIRE 16 -1 (1300 3625)(1300 3750);
WIRE 16 -1 (2200 3625)(1750 3625);
WIRE 16 -1 (1750 3625)(1750 3750);
WIRE 16 -1 (2650 3625)(2200 3625);
WIRE 16 -1 (2200 3625)(2200 3750);
WIRE 16 -1 (3100 3625)(2650 3625);
WIRE 16 -1 (2650 3625)(2650 3750);
WIRE 16 -1 (3550 3625)(3100 3625);
WIRE 16 -1 (3100 3625)(3100 3750);
WIRE 16 -1 (4000 3625)(3550 3625);
WIRE 16 -1 (3550 3625)(3550 3750);
WIRE 16 -1 (4400 3625)(4000 3625);
WIRE 16 -1 (4000 3625)(4000 3750);
WIRE 16 -1 (4400 3625)(4400 3750);
WIRE 16 -1 (4400 3525)(4400 3625);
WIRE 16 -1 (4400 3250)(4400 3325);
WIRE 16 -1 (4400 3325)(4000 3325);
WIRE 16 -1 (4000 3325)(4000 3250);
WIRE 16 -1 (4000 3325)(3550 3325);
WIRE 16 -1 (3550 3250)(3550 3325);
WIRE 16 -1 (3550 3325)(3100 3325);
WIRE 16 -1 (3100 3250)(3100 3325);
WIRE 16 -1 (3100 3325)(2650 3325);
WIRE 16 -1 (2650 3325)(2650 3250);
WIRE 16 -1 (2650 3325)(2200 3325);
WIRE 16 -1 (2200 3250)(2200 3325);
WIRE 16 -1 (2200 3325)(1750 3325);
WIRE 16 -1 (1750 3250)(1750 3325);
WIRE 16 -1 (1750 3325)(1300 3325);
WIRE 16 -1 (1300 3325)(1300 3250);
WIRE 16 -1 (1300 3325)(850 3325);
WIRE 16 -1 (850 3325)(400 3325);
WIRE 16 -1 (850 3250)(850 3325);
WIRE 16 -1 (400 3325)(400 3375);
WIRE 16 -1 (400 3325)(400 3250);
WIRE 16 -1 (4400 4650)(4400 4725);
WIRE 16 -1 (4400 4725)(4000 4725);
WIRE 16 -1 (4000 4725)(4000 4650);
WIRE 16 -1 (4000 4725)(3550 4725);
WIRE 16 -1 (3550 4650)(3550 4725);
WIRE 16 -1 (3550 4725)(3100 4725);
WIRE 16 -1 (3100 4650)(3100 4725);
WIRE 16 -1 (3100 4725)(2650 4725);
WIRE 16 -1 (2650 4725)(2650 4650);
WIRE 16 -1 (2650 4725)(2200 4725);
WIRE 16 -1 (2200 4650)(2200 4725);
WIRE 16 -1 (2200 4725)(1750 4725);
WIRE 16 -1 (1750 4650)(1750 4725);
WIRE 16 -1 (1750 4725)(1300 4725);
WIRE 16 -1 (1300 4725)(1300 4650);
WIRE 16 -1 (1300 4725)(850 4725);
WIRE 16 -1 (850 4725)(400 4725);
WIRE 16 -1 (850 4650)(850 4725);
WIRE 16 -1 (400 4725)(400 4775);
WIRE 16 -1 (400 4725)(400 4650);
WIRE 16 -1 (850 4325)(400 4325);
WIRE 16 -1 (1300 4325)(850 4325);
WIRE 16 -1 (850 4325)(850 4450);
WIRE 16 -1 (400 4325)(400 4450);
WIRE 16 -1 (1750 4325)(1300 4325);
WIRE 16 -1 (1300 4325)(1300 4450);
WIRE 16 -1 (2200 4325)(1750 4325);
WIRE 16 -1 (1750 4325)(1750 4450);
WIRE 16 -1 (2650 4325)(2200 4325);
WIRE 16 -1 (2200 4325)(2200 4450);
WIRE 16 -1 (3100 4325)(2650 4325);
WIRE 16 -1 (2650 4325)(2650 4450);
WIRE 16 -1 (3550 4325)(3100 4325);
WIRE 16 -1 (3100 4325)(3100 4450);
WIRE 16 -1 (4000 4325)(3550 4325);
WIRE 16 -1 (3550 4325)(3550 4450);
WIRE 16 -1 (4400 4325)(4000 4325);
WIRE 16 -1 (4000 4325)(4000 4450);
WIRE 16 -1 (4400 4325)(4400 4450);
WIRE 16 -1 (4400 4225)(4400 4325);
WIRE 16 -1 (400 5000)(400 5125);
WIRE 16 -1 (850 5000)(400 5000);
WIRE 16 -1 (1300 5000)(850 5000);
WIRE 16 -1 (850 5000)(850 5125);
WIRE 16 -1 (1300 5000)(1300 5125);
WIRE 16 -1 (1750 5000)(1300 5000);
WIRE 16 -1 (2200 5000)(1750 5000);
WIRE 16 -1 (1750 5000)(1750 5125);
WIRE 16 -1 (2200 5000)(2200 5125);
WIRE 16 -1 (2650 5000)(2200 5000);
WIRE 16 -1 (3100 5000)(2650 5000);
WIRE 16 -1 (2650 5000)(2650 5125);
WIRE 16 -1 (3100 5000)(3100 5125);
WIRE 16 -1 (3550 5000)(3100 5000);
WIRE 16 -1 (3550 5000)(3550 5125);
WIRE 16 -1 (4000 5000)(3550 5000);
WIRE 16 -1 (4400 5000)(4000 5000);
WIRE 16 -1 (4000 5000)(4000 5125);
WIRE 16 -1 (4400 5000)(4400 5125);
WIRE 16 -1 (4400 4900)(4400 5000);
WIRE 16 -1 (4400 5975)(4400 6050);
WIRE 16 -1 (4400 6050)(4000 6050);
WIRE 16 -1 (4000 6050)(4000 5975);
WIRE 16 -1 (4000 6050)(3550 6050);
WIRE 16 -1 (3550 5975)(3550 6050);
WIRE 16 -1 (3550 6050)(3100 6050);
WIRE 16 -1 (3100 5975)(3100 6050);
WIRE 16 -1 (3100 6050)(2650 6050);
WIRE 16 -1 (2650 6050)(2650 5975);
WIRE 16 -1 (2650 6050)(2200 6050);
WIRE 16 -1 (2200 5975)(2200 6050);
WIRE 16 -1 (2200 6050)(1750 6050);
WIRE 16 -1 (1750 5975)(1750 6050);
WIRE 16 -1 (1750 6050)(1300 6050);
WIRE 16 -1 (1300 6050)(1300 5975);
WIRE 16 -1 (1300 6050)(850 6050);
WIRE 16 -1 (850 6050)(400 6050);
WIRE 16 -1 (850 5975)(850 6050);
WIRE 16 -1 (400 6050)(400 6100);
WIRE 16 -1 (400 6050)(400 5975);
WIRE 16 -1 (850 5650)(400 5650);
WIRE 16 -1 (1300 5650)(850 5650);
WIRE 16 -1 (850 5650)(850 5775);
WIRE 16 -1 (400 5650)(400 5775);
WIRE 16 -1 (1750 5650)(1300 5650);
WIRE 16 -1 (1300 5650)(1300 5775);
WIRE 16 -1 (2200 5650)(1750 5650);
WIRE 16 -1 (1750 5650)(1750 5775);
WIRE 16 -1 (2650 5650)(2200 5650);
WIRE 16 -1 (2200 5650)(2200 5775);
WIRE 16 -1 (3100 5650)(2650 5650);
WIRE 16 -1 (2650 5650)(2650 5775);
WIRE 16 -1 (3550 5650)(3100 5650);
WIRE 16 -1 (3100 5650)(3100 5775);
WIRE 16 -1 (4000 5650)(3550 5650);
WIRE 16 -1 (3550 5650)(3550 5775);
WIRE 16 -1 (4400 5650)(4000 5650);
WIRE 16 -1 (4000 5650)(4000 5775);
WIRE 16 -1 (4400 5650)(4400 5775);
WIRE 16 -1 (4400 5550)(4400 5650);
WIRE 16 -1 (4400 5325)(4400 5400);
WIRE 16 -1 (4400 5400)(4000 5400);
WIRE 16 -1 (4000 5400)(4000 5325);
WIRE 16 -1 (4000 5400)(3550 5400);
WIRE 16 -1 (3550 5325)(3550 5400);
WIRE 16 -1 (3550 5400)(3100 5400);
WIRE 16 -1 (3100 5325)(3100 5400);
WIRE 16 -1 (3100 5400)(2650 5400);
WIRE 16 -1 (2650 5400)(2650 5325);
WIRE 16 -1 (2650 5400)(2200 5400);
WIRE 16 -1 (2200 5325)(2200 5400);
WIRE 16 -1 (2200 5400)(1750 5400);
WIRE 16 -1 (1750 5325)(1750 5400);
WIRE 16 -1 (1750 5400)(1300 5400);
WIRE 16 -1 (1300 5400)(1300 5325);
WIRE 16 -1 (1300 5400)(850 5400);
WIRE 16 -1 (850 5400)(400 5400);
WIRE 16 -1 (850 5325)(850 5400);
WIRE 16 -1 (400 5400)(400 5450);
WIRE 16 -1 (400 5400)(400 5325);
WIRE 16 3135 (225 600)(4725 600);
WIRE 16 3135 (225 600)(225 6475);
WIRE 16 3135 (4725 600)(4725 6475);
WIRE 16 3135 (225 6475)(4725 6475);
WIRE 16 -1 (5450 1800)(5000 1800);
WIRE 16 -1 (5900 1800)(5450 1800);
WIRE 16 -1 (5450 1800)(5450 1925);
WIRE 16 -1 (5000 1800)(5000 1925);
WIRE 16 -1 (6350 1800)(5900 1800);
WIRE 16 -1 (5900 1800)(5900 1925);
WIRE 16 -1 (6800 1800)(6350 1800);
WIRE 16 -1 (6350 1800)(6350 1925);
WIRE 16 -1 (7250 1800)(6800 1800);
WIRE 16 -1 (6800 1800)(6800 1925);
WIRE 16 -1 (7700 1800)(7250 1800);
WIRE 16 -1 (7250 1800)(7250 1925);
WIRE 16 -1 (8150 1800)(7700 1800);
WIRE 16 -1 (7700 1800)(7700 1925);
WIRE 16 -1 (8600 1800)(8150 1800);
WIRE 16 -1 (8150 1800)(8150 1925);
WIRE 16 -1 (9000 1800)(8600 1800);
WIRE 16 -1 (8600 1800)(8600 1925);
WIRE 16 -1 (9000 1800)(9000 1925);
WIRE 16 -1 (9000 1700)(9000 1800);
WIRE 16 -1 (9000 1475)(9000 1550);
WIRE 16 -1 (9000 1550)(8600 1550);
WIRE 16 -1 (8600 1550)(8600 1475);
WIRE 16 -1 (8600 1550)(8150 1550);
WIRE 16 -1 (8150 1475)(8150 1550);
WIRE 16 -1 (8150 1550)(7700 1550);
WIRE 16 -1 (7700 1475)(7700 1550);
WIRE 16 -1 (7700 1550)(7250 1550);
WIRE 16 -1 (7250 1550)(7250 1475);
WIRE 16 -1 (7250 1550)(6800 1550);
WIRE 16 -1 (6800 1475)(6800 1550);
WIRE 16 -1 (6800 1550)(6350 1550);
WIRE 16 -1 (6350 1475)(6350 1550);
WIRE 16 -1 (6350 1550)(5900 1550);
WIRE 16 -1 (5900 1550)(5900 1475);
WIRE 16 -1 (5900 1550)(5450 1550);
WIRE 16 -1 (5450 1550)(5000 1550);
WIRE 16 -1 (5450 1475)(5450 1550);
WIRE 16 -1 (5000 1550)(5000 1600);
WIRE 16 -1 (5000 1550)(5000 1475);
WIRE 16 -1 (5450 1150)(5000 1150);
WIRE 16 -1 (5900 1150)(5450 1150);
WIRE 16 -1 (5450 1150)(5450 1275);
WIRE 16 -1 (5000 1150)(5000 1275);
WIRE 16 -1 (6350 1150)(5900 1150);
WIRE 16 -1 (5900 1150)(5900 1275);
WIRE 16 -1 (6800 1150)(6350 1150);
WIRE 16 -1 (6350 1150)(6350 1275);
WIRE 16 -1 (7250 1150)(6800 1150);
WIRE 16 -1 (6800 1150)(6800 1275);
WIRE 16 -1 (7700 1150)(7250 1150);
WIRE 16 -1 (7250 1150)(7250 1275);
WIRE 16 -1 (8150 1150)(7700 1150);
WIRE 16 -1 (7700 1150)(7700 1275);
WIRE 16 -1 (8600 1150)(8150 1150);
WIRE 16 -1 (8150 1275)(8150 1150);
WIRE 16 -1 (9000 1150)(8600 1150);
WIRE 16 -1 (8600 1150)(8600 1275);
WIRE 16 -1 (9000 1050)(9000 1150);
WIRE 16 -1 (9000 1150)(9000 1275);
WIRE 16 -1 (5450 950)(5000 950);
WIRE 16 -1 (5450 875)(5450 950);
WIRE 16 -1 (5000 950)(5000 1000);
WIRE 16 -1 (5000 950)(5000 875);
WIRE 16 -1 (5450 550)(5000 550);
WIRE 16 -1 (5450 550)(5450 675);
WIRE 16 -1 (5450 500)(5450 550);
WIRE 16 -1 (5000 550)(5000 675);
WIRE 16 -1 (9000 3425)(9000 3500);
WIRE 16 -1 (9000 3500)(8600 3500);
WIRE 16 -1 (8600 3500)(8600 3425);
WIRE 16 -1 (8600 3500)(8150 3500);
WIRE 16 -1 (8150 3425)(8150 3500);
WIRE 16 -1 (8150 3500)(7700 3500);
WIRE 16 -1 (7700 3425)(7700 3500);
WIRE 16 -1 (7700 3500)(7250 3500);
WIRE 16 -1 (7250 3500)(7250 3425);
WIRE 16 -1 (7250 3500)(6800 3500);
WIRE 16 -1 (6800 3425)(6800 3500);
WIRE 16 -1 (6800 3500)(6350 3500);
WIRE 16 -1 (6350 3425)(6350 3500);
WIRE 16 -1 (6350 3500)(5900 3500);
WIRE 16 -1 (5900 3500)(5900 3425);
WIRE 16 -1 (5900 3500)(5450 3500);
WIRE 16 -1 (5450 3500)(5000 3500);
WIRE 16 -1 (5450 3425)(5450 3500);
WIRE 16 -1 (5000 3500)(5000 3550);
WIRE 16 -1 (5000 3500)(5000 3425);
WIRE 16 -1 (5450 3100)(5000 3100);
WIRE 16 -1 (5900 3100)(5450 3100);
WIRE 16 -1 (5450 3100)(5450 3225);
WIRE 16 -1 (5000 3100)(5000 3225);
WIRE 16 -1 (6350 3100)(5900 3100);
WIRE 16 -1 (5900 3100)(5900 3225);
WIRE 16 -1 (6800 3100)(6350 3100);
WIRE 16 -1 (6350 3100)(6350 3225);
WIRE 16 -1 (7250 3100)(6800 3100);
WIRE 16 -1 (6800 3100)(6800 3225);
WIRE 16 -1 (7700 3100)(7250 3100);
WIRE 16 -1 (7250 3100)(7250 3225);
WIRE 16 -1 (8150 3100)(7700 3100);
WIRE 16 -1 (7700 3100)(7700 3225);
WIRE 16 -1 (8600 3100)(8150 3100);
WIRE 16 -1 (8150 3100)(8150 3225);
WIRE 16 -1 (9000 3100)(8600 3100);
WIRE 16 -1 (8600 3100)(8600 3225);
WIRE 16 -1 (9000 3000)(9000 3100);
WIRE 16 -1 (9000 3100)(9000 3225);
WIRE 16 -1 (9000 2750)(9000 2825);
WIRE 16 -1 (9000 2825)(8600 2825);
WIRE 16 -1 (8600 2825)(8600 2750);
WIRE 16 -1 (8600 2825)(8150 2825);
WIRE 16 -1 (8150 2750)(8150 2825);
WIRE 16 -1 (8150 2825)(7700 2825);
WIRE 16 -1 (7700 2750)(7700 2825);
WIRE 16 -1 (7700 2825)(7250 2825);
WIRE 16 -1 (7250 2825)(7250 2750);
WIRE 16 -1 (7250 2825)(6800 2825);
WIRE 16 -1 (6800 2750)(6800 2825);
WIRE 16 -1 (6800 2825)(6350 2825);
WIRE 16 -1 (6350 2750)(6350 2825);
WIRE 16 -1 (6350 2825)(5900 2825);
WIRE 16 -1 (5900 2825)(5900 2750);
WIRE 16 -1 (5900 2825)(5450 2825);
WIRE 16 -1 (5450 2825)(5000 2825);
WIRE 16 -1 (5450 2750)(5450 2825);
WIRE 16 -1 (5000 2825)(5000 2875);
WIRE 16 -1 (5000 2825)(5000 2750);
WIRE 16 -1 (5450 2425)(5000 2425);
WIRE 16 -1 (5900 2425)(5450 2425);
WIRE 16 -1 (5450 2425)(5450 2550);
WIRE 16 -1 (5000 2425)(5000 2550);
WIRE 16 -1 (6350 2425)(5900 2425);
WIRE 16 -1 (5900 2425)(5900 2550);
WIRE 16 -1 (6800 2425)(6350 2425);
WIRE 16 -1 (6350 2425)(6350 2550);
WIRE 16 -1 (7250 2425)(6800 2425);
WIRE 16 -1 (6800 2425)(6800 2550);
WIRE 16 -1 (7700 2425)(7250 2425);
WIRE 16 -1 (7250 2425)(7250 2550);
WIRE 16 -1 (8150 2425)(7700 2425);
WIRE 16 -1 (7700 2425)(7700 2550);
WIRE 16 -1 (8600 2425)(8150 2425);
WIRE 16 -1 (8150 2425)(8150 2550);
WIRE 16 -1 (9000 2425)(8600 2425);
WIRE 16 -1 (8600 2425)(8600 2550);
WIRE 16 -1 (9000 2350)(9000 2425);
WIRE 16 -1 (9000 2425)(9000 2550);
WIRE 16 -1 (9000 2125)(9000 2200);
WIRE 16 -1 (9000 2200)(8600 2200);
WIRE 16 -1 (8600 2200)(8600 2125);
WIRE 16 -1 (8600 2200)(8150 2200);
WIRE 16 -1 (8150 2125)(8150 2200);
WIRE 16 -1 (8150 2200)(7700 2200);
WIRE 16 -1 (7700 2125)(7700 2200);
WIRE 16 -1 (7700 2200)(7250 2200);
WIRE 16 -1 (7250 2200)(7250 2125);
WIRE 16 -1 (7250 2200)(6800 2200);
WIRE 16 -1 (6800 2125)(6800 2200);
WIRE 16 -1 (6800 2200)(6350 2200);
WIRE 16 -1 (6350 2125)(6350 2200);
WIRE 16 -1 (6350 2200)(5900 2200);
WIRE 16 -1 (5900 2200)(5900 2125);
WIRE 16 -1 (5900 2200)(5450 2200);
WIRE 16 -1 (5450 2200)(5000 2200);
WIRE 16 -1 (5450 2125)(5450 2200);
WIRE 16 -1 (5000 2200)(5000 2250);
WIRE 16 -1 (5000 2200)(5000 2125);
WIRE 16 -1 (6350 3975)(6350 4075);
WIRE 16 -1 (6350 4075)(6350 4200);
WIRE 16 -1 (6350 4075)(5900 4075);
WIRE 16 -1 (5900 4075)(5900 4200);
WIRE 16 -1 (5900 4075)(5450 4075);
WIRE 16 -1 (5450 4075)(5450 4200);
WIRE 16 -1 (5450 4075)(5000 4075);
WIRE 16 -1 (5000 4075)(5000 4200);
WIRE 16 -1 (8975 5975)(8975 6050);
WIRE 16 -1 (8975 6050)(8575 6050);
WIRE 16 -1 (8575 6050)(8575 5975);
WIRE 16 -1 (8575 6050)(8125 6050);
WIRE 16 -1 (8125 5975)(8125 6050);
WIRE 16 -1 (8125 6050)(7675 6050);
WIRE 16 -1 (7675 5975)(7675 6050);
WIRE 16 -1 (7675 6050)(7225 6050);
WIRE 16 -1 (7225 6050)(7225 5975);
WIRE 16 -1 (7225 6050)(6775 6050);
WIRE 16 -1 (6775 5975)(6775 6050);
WIRE 16 -1 (6775 6050)(6325 6050);
WIRE 16 -1 (6325 5975)(6325 6050);
WIRE 16 -1 (6325 6050)(5875 6050);
WIRE 16 -1 (5875 6050)(5875 5975);
WIRE 16 -1 (5875 6050)(5425 6050);
WIRE 16 -1 (5425 6050)(4975 6050);
WIRE 16 -1 (5425 5975)(5425 6050);
WIRE 16 -1 (4975 6050)(4975 6100);
WIRE 16 -1 (4975 6050)(4975 5975);
WIRE 16 -1 (5425 5650)(4975 5650);
WIRE 16 -1 (5875 5650)(5425 5650);
WIRE 16 -1 (5425 5650)(5425 5775);
WIRE 16 -1 (4975 5650)(4975 5775);
WIRE 16 -1 (6325 5650)(5875 5650);
WIRE 16 -1 (5875 5650)(5875 5775);
WIRE 16 -1 (6775 5650)(6325 5650);
WIRE 16 -1 (6325 5650)(6325 5775);
WIRE 16 -1 (7225 5650)(6775 5650);
WIRE 16 -1 (6775 5650)(6775 5775);
WIRE 16 -1 (7675 5650)(7225 5650);
WIRE 16 -1 (7225 5650)(7225 5775);
WIRE 16 -1 (8125 5650)(7675 5650);
WIRE 16 -1 (7675 5650)(7675 5775);
WIRE 16 -1 (8575 5650)(8125 5650);
WIRE 16 -1 (8125 5650)(8125 5775);
WIRE 16 -1 (8975 5650)(8575 5650);
WIRE 16 -1 (8575 5650)(8575 5775);
WIRE 16 -1 (8975 5650)(8975 5775);
WIRE 16 -1 (8975 5550)(8975 5650);
WIRE 16 -1 (8975 5175)(8975 5250);
WIRE 16 -1 (8975 5250)(8575 5250);
WIRE 16 -1 (8575 5250)(8575 5175);
WIRE 16 -1 (8575 5250)(8125 5250);
WIRE 16 -1 (8125 5175)(8125 5250);
WIRE 16 -1 (8125 5250)(7675 5250);
WIRE 16 -1 (7675 5175)(7675 5250);
WIRE 16 -1 (7675 5250)(7225 5250);
WIRE 16 -1 (7225 5250)(7225 5175);
WIRE 16 -1 (7225 5250)(6775 5250);
WIRE 16 -1 (6775 5175)(6775 5250);
WIRE 16 -1 (6775 5250)(6325 5250);
WIRE 16 -1 (6325 5175)(6325 5250);
WIRE 16 -1 (6325 5250)(5875 5250);
WIRE 16 -1 (5875 5250)(5875 5175);
WIRE 16 -1 (5875 5250)(5425 5250);
WIRE 16 -1 (5425 5250)(4975 5250);
WIRE 16 -1 (5425 5175)(5425 5250);
WIRE 16 -1 (4975 5250)(4975 5300);
WIRE 16 -1 (4975 5250)(4975 5175);
WIRE 16 -1 (5425 4850)(4975 4850);
WIRE 16 -1 (5875 4850)(5425 4850);
WIRE 16 -1 (5425 4850)(5425 4975);
WIRE 16 -1 (4975 4850)(4975 4975);
WIRE 16 -1 (6325 4850)(5875 4850);
WIRE 16 -1 (5875 4850)(5875 4975);
WIRE 16 -1 (6775 4850)(6325 4850);
WIRE 16 -1 (6325 4850)(6325 4975);
WIRE 16 -1 (7225 4850)(6775 4850);
WIRE 16 -1 (6775 4850)(6775 4975);
WIRE 16 -1 (7675 4850)(7225 4850);
WIRE 16 -1 (7225 4850)(7225 4975);
WIRE 16 -1 (8125 4850)(7675 4850);
WIRE 16 -1 (7675 4850)(7675 4975);
WIRE 16 -1 (8575 4850)(8125 4850);
WIRE 16 -1 (8125 4850)(8125 4975);
WIRE 16 -1 (8975 4850)(8575 4850);
WIRE 16 -1 (8575 4850)(8575 4975);
WIRE 16 -1 (8975 4850)(8975 4975);
WIRE 16 -1 (8975 4750)(8975 4850);
WIRE 16 -1 (5450 4475)(5000 4475);
WIRE 16 -1 (5900 4475)(5450 4475);
WIRE 16 -1 (5450 4400)(5450 4475);
WIRE 16 -1 (5000 4475)(5000 4525);
WIRE 16 -1 (5000 4475)(5000 4400);
WIRE 16 -1 (6350 4475)(5900 4475);
WIRE 16 -1 (5900 4475)(5900 4400);
WIRE 16 -1 (6350 4400)(6350 4475);
WIRE 16 3135 (4850 3850)(9300 3850);
WIRE 16 3135 (4850 3850)(4850 6475);
WIRE 16 3135 (9300 3850)(9300 6475);
WIRE 16 3135 (4850 6475)(9300 6475);
DOT 1 (850 850);
DOT 1 (400 1250);
DOT 1 (850 1250);
DOT 1 (850 1575);
DOT 1 (1750 850);
DOT 1 (1300 850);
DOT 1 (1300 1250);
DOT 1 (1300 1575);
DOT 1 (1750 1250);
DOT 1 (1750 1575);
DOT 1 (400 1975);
DOT 1 (400 2650);
DOT 1 (850 1975);
DOT 1 (850 2250);
DOT 1 (850 2650);
DOT 1 (850 2925);
DOT 1 (400 3325);
DOT 1 (850 3325);
DOT 1 (850 3625);
DOT 1 (1300 1975);
DOT 1 (1300 2250);
DOT 1 (1300 2650);
DOT 1 (1750 1975);
DOT 1 (1750 2250);
DOT 1 (1750 2650);
DOT 1 (1750 2925);
DOT 1 (1300 2925);
DOT 1 (1300 3325);
DOT 1 (1300 3625);
DOT 1 (1750 3325);
DOT 1 (1750 3625);
DOT 1 (2200 850);
DOT 1 (2650 850);
DOT 1 (2200 1250);
DOT 1 (2200 1575);
DOT 1 (2650 1250);
DOT 1 (2650 1575);
DOT 1 (3100 850);
DOT 1 (3100 1575);
DOT 1 (3550 1575);
DOT 1 (4000 1575);
DOT 1 (2200 1975);
DOT 1 (2200 2250);
DOT 1 (2200 2650);
DOT 1 (2650 1975);
DOT 1 (2650 2250);
DOT 1 (2650 2650);
DOT 1 (2650 2925);
DOT 1 (2200 2925);
DOT 1 (2200 3325);
DOT 1 (2200 3625);
DOT 1 (2650 3325);
DOT 1 (2650 3625);
DOT 1 (3100 1975);
DOT 1 (3100 2250);
DOT 1 (3550 1975);
DOT 1 (3550 2250);
DOT 1 (3100 2650);
DOT 1 (3550 2650);
DOT 1 (4000 1975);
DOT 1 (4000 2250);
DOT 1 (4000 2650);
DOT 1 (4000 2925);
DOT 1 (3550 2925);
DOT 1 (3100 2925);
DOT 1 (3100 3325);
DOT 1 (3550 3325);
DOT 1 (3100 3625);
DOT 1 (3550 3625);
DOT 1 (4000 3325);
DOT 1 (4000 3625);
DOT 1 (400 4025);
DOT 1 (400 4725);
DOT 1 (850 4025);
DOT 1 (850 4325);
DOT 1 (850 4725);
DOT 1 (400 5400);
DOT 1 (850 5000);
DOT 1 (850 5400);
DOT 1 (850 5650);
DOT 1 (1300 4025);
DOT 1 (1300 4325);
DOT 1 (1300 4725);
DOT 1 (1750 4025);
DOT 1 (1750 4325);
DOT 1 (1750 4725);
DOT 1 (1300 5000);
DOT 1 (1300 5400);
DOT 1 (1300 5650);
DOT 1 (1750 5000);
DOT 1 (1750 5400);
DOT 1 (1750 5650);
DOT 1 (1300 6050);
DOT 1 (1750 6050);
DOT 1 (2200 4025);
DOT 1 (2200 4325);
DOT 1 (2200 4725);
DOT 1 (2650 4025);
DOT 1 (2650 4325);
DOT 1 (2650 4725);
DOT 1 (2200 5000);
DOT 1 (2200 5400);
DOT 1 (2200 5650);
DOT 1 (2650 5000);
DOT 1 (2650 5400);
DOT 1 (2650 5650);
DOT 1 (3100 4025);
DOT 1 (3100 4325);
DOT 1 (3550 4025);
DOT 1 (3550 4325);
DOT 1 (3100 4725);
DOT 1 (3550 4725);
DOT 1 (4000 4025);
DOT 1 (4000 4325);
DOT 1 (4000 4725);
DOT 1 (3100 5000);
DOT 1 (3100 5400);
DOT 1 (3550 5000);
DOT 1 (3550 5400);
DOT 1 (3100 5650);
DOT 1 (3550 5650);
DOT 1 (4000 5000);
DOT 1 (4000 5400);
DOT 1 (4000 5650);
DOT 1 (2200 6050);
DOT 1 (2650 6050);
DOT 1 (3100 6050);
DOT 1 (3550 6050);
DOT 1 (4000 6050);
DOT 1 (4400 1575);
DOT 1 (5000 950);
DOT 1 (5000 1550);
DOT 1 (5450 550);
DOT 1 (5450 1150);
DOT 1 (5450 1550);
DOT 1 (5450 1800);
DOT 1 (5900 1150);
DOT 1 (5900 1550);
DOT 1 (5900 1800);
DOT 1 (4400 2250);
DOT 1 (5000 2200);
DOT 1 (5000 2825);
DOT 1 (4400 2925);
DOT 1 (5000 3500);
DOT 1 (5450 2200);
DOT 1 (5450 2425);
DOT 1 (5450 2825);
DOT 1 (5900 2200);
DOT 1 (5900 2825);
DOT 1 (5900 2425);
DOT 1 (5450 3100);
DOT 1 (5450 3500);
DOT 1 (5900 3100);
DOT 1 (5900 3500);
DOT 1 (6350 1150);
DOT 1 (6350 1550);
DOT 1 (6350 1800);
DOT 1 (6800 1150);
DOT 1 (6800 1550);
DOT 1 (6800 1800);
DOT 1 (7250 1150);
DOT 1 (7250 1550);
DOT 1 (7250 1800);
DOT 1 (7700 1150);
DOT 1 (8150 1150);
DOT 1 (7700 1550);
DOT 1 (7700 1800);
DOT 1 (8150 1550);
DOT 1 (8150 1800);
DOT 1 (6350 2200);
DOT 1 (6350 2425);
DOT 1 (6350 2825);
DOT 1 (6800 2200);
DOT 1 (6800 2425);
DOT 1 (6800 2825);
DOT 1 (6350 3100);
DOT 1 (6350 3500);
DOT 1 (6800 3100);
DOT 1 (6800 3500);
DOT 1 (7250 2200);
DOT 1 (7250 2425);
DOT 1 (7250 2825);
DOT 1 (7700 2200);
DOT 1 (8150 2200);
DOT 1 (7700 2425);
DOT 1 (7700 2825);
DOT 1 (8150 2425);
DOT 1 (8150 2825);
DOT 1 (7250 3100);
DOT 1 (7250 3500);
DOT 1 (7700 3100);
DOT 1 (8150 3100);
DOT 1 (7700 3500);
DOT 1 (8150 3500);
DOT 1 (4400 4325);
DOT 1 (5000 4475);
DOT 1 (4400 5000);
DOT 1 (4400 5650);
DOT 1 (4975 5250);
DOT 1 (5450 4075);
DOT 1 (5450 4475);
DOT 1 (5425 4850);
DOT 1 (5900 4075);
DOT 1 (5875 4850);
DOT 1 (5900 4475);
DOT 1 (5425 5250);
DOT 1 (5425 5650);
DOT 1 (5875 5250);
DOT 1 (5875 5650);
DOT 1 (4975 6050);
DOT 1 (5425 6050);
DOT 1 (5875 6050);
DOT 1 (6350 4075);
DOT 1 (6325 4850);
DOT 1 (6775 4850);
DOT 1 (6325 5250);
DOT 1 (6325 5650);
DOT 1 (6775 5250);
DOT 1 (6775 5650);
DOT 1 (7675 4850);
DOT 1 (7225 4850);
DOT 1 (8125 4850);
DOT 1 (7225 5250);
DOT 1 (7675 5250);
DOT 1 (7225 5650);
DOT 1 (7675 5650);
DOT 1 (8125 5250);
DOT 1 (8125 5650);
DOT 1 (6325 6050);
DOT 1 (6775 6050);
DOT 1 (7225 6050);
DOT 1 (7675 6050);
DOT 1 (8125 6050);
DOT 1 (8600 1150);
DOT 1 (8600 1550);
DOT 1 (8600 1800);
DOT 1 (9000 1150);
DOT 1 (9000 1800);
DOT 1 (8600 2200);
DOT 1 (8600 2425);
DOT 1 (8600 2825);
DOT 1 (9000 2425);
DOT 1 (8600 3100);
DOT 1 (8600 3500);
DOT 1 (9000 3100);
DOT 1 (8575 4850);
DOT 1 (8975 4850);
DOT 1 (8575 5250);
DOT 1 (8575 5650);
DOT 1 (8975 5650);
DOT 1 (8575 6050);
DOT 1 (850 6050);
DOT 1 (400 6050);
DOT 1 (4400 3625);
FORCENOTE
PVDDCR_SOC_P1: 77PCS 22UF ON BOT
(400 6275) 0;
DISPLAY LEFT (400 6275);
DISPLAY 2.510638 (400 6275);
PAINT WHITE (400 6275);
FORCENOTE
5
(2175 1300) 0;
DISPLAY LEFT (2175 1300);
DISPLAY 1.021277 (2175 1300);
PAINT SKYBLUE (2175 1300);
FORCENOTE
5
(2175 2025) 0;
DISPLAY LEFT (2175 2025);
DISPLAY 1.021277 (2175 2025);
PAINT SKYBLUE (2175 2025);
FORCENOTE
5
(2200 2700) 0;
DISPLAY LEFT (2200 2700);
DISPLAY 1.021277 (2200 2700);
PAINT SKYBLUE (2200 2700);
FORCENOTE
5
(2175 3375) 0;
DISPLAY LEFT (2175 3375);
DISPLAY 1.021277 (2175 3375);
PAINT SKYBLUE (2175 3375);
FORCENOTE
5
(2175 4075) 0;
DISPLAY LEFT (2175 4075);
DISPLAY 1.021277 (2175 4075);
PAINT SKYBLUE (2175 4075);
FORCENOTE
5
(2200 4750) 0;
DISPLAY LEFT (2200 4750);
DISPLAY 1.021277 (2200 4750);
PAINT SKYBLUE (2200 4750);
FORCENOTE
5
(2175 5450) 0;
DISPLAY LEFT (2175 5450);
DISPLAY 1.021277 (2175 5450);
PAINT SKYBLUE (2175 5450);
FORCENOTE
5
(2175 6100) 0;
DISPLAY LEFT (2175 6100);
DISPLAY 1.021277 (2175 6100);
PAINT SKYBLUE (2175 6100);
FORCENOTE
10
(4350 2000) 0;
DISPLAY LEFT (4350 2000);
DISPLAY 1.021277 (4350 2000);
PAINT SKYBLUE (4350 2000);
FORCENOTE
10
(4375 2675) 0;
DISPLAY LEFT (4375 2675);
DISPLAY 1.021277 (4375 2675);
PAINT SKYBLUE (4375 2675);
FORCENOTE
10
(4375 3350) 0;
DISPLAY LEFT (4375 3350);
DISPLAY 1.021277 (4375 3350);
PAINT SKYBLUE (4375 3350);
FORCENOTE
5
(6775 1600) 0;
DISPLAY LEFT (6775 1600);
DISPLAY 1.021277 (6775 1600);
PAINT SKYBLUE (6775 1600);
FORCENOTE
5
(6775 2250) 0;
DISPLAY LEFT (6775 2250);
DISPLAY 1.021277 (6775 2250);
PAINT SKYBLUE (6775 2250);
FORCENOTE
5
(6775 2850) 0;
DISPLAY LEFT (6775 2850);
DISPLAY 1.021277 (6775 2850);
PAINT SKYBLUE (6775 2850);
FORCENOTE
5
(6775 3525) 0;
DISPLAY LEFT (6775 3525);
DISPLAY 1.021277 (6775 3525);
PAINT SKYBLUE (6775 3525);
FORCENOTE
10
(4375 4050) 0;
DISPLAY LEFT (4375 4050);
DISPLAY 1.021277 (4375 4050);
PAINT SKYBLUE (4375 4050);
FORCENOTE
10
(4350 4750) 0;
DISPLAY LEFT (4350 4750);
DISPLAY 1.021277 (4350 4750);
PAINT SKYBLUE (4350 4750);
FORCENOTE
10
(4350 5425) 0;
DISPLAY LEFT (4350 5425);
DISPLAY 1.021277 (4350 5425);
PAINT SKYBLUE (4350 5425);
FORCENOTE
10
(4350 6100) 0;
DISPLAY LEFT (4350 6100);
DISPLAY 1.021277 (4350 6100);
PAINT SKYBLUE (4350 6100);
FORCENOTE
5
(6750 5300) 0;
DISPLAY LEFT (6750 5300);
DISPLAY 1.021277 (6750 5300);
PAINT SKYBLUE (6750 5300);
FORCENOTE
5
(6750 6100) 0;
DISPLAY LEFT (6750 6100);
DISPLAY 1.021277 (6750 6100);
PAINT SKYBLUE (6750 6100);
FORCENOTE
PVDD11_S3_P1: 42PCS 22UF ON BOT
(5375 3625) 0;
DISPLAY LEFT (5375 3625);
DISPLAY 2.510638 (5375 3625);
PAINT WHITE (5375 3625);
FORCENOTE
10
(8950 2225) 0;
DISPLAY LEFT (8950 2225);
DISPLAY 1.021277 (8950 2225);
PAINT SKYBLUE (8950 2225);
FORCENOTE
10
(8950 2850) 0;
DISPLAY LEFT (8950 2850);
DISPLAY 1.021277 (8950 2850);
PAINT SKYBLUE (8950 2850);
FORCENOTE
10
(8950 3525) 0;
DISPLAY LEFT (8950 3525);
DISPLAY 1.021277 (8950 3525);
PAINT SKYBLUE (8950 3525);
FORCENOTE
10
(8925 5300) 0;
DISPLAY LEFT (8925 5300);
DISPLAY 1.021277 (8925 5300);
PAINT SKYBLUE (8925 5300);
FORCENOTE
10
(8925 6100) 0;
DISPLAY LEFT (8925 6100);
DISPLAY 1.021277 (8925 6100);
PAINT SKYBLUE (8925 6100);
FORCENOTE
PVDDIO_P1: 24PCS 22UF ON BOT
(4950 6275) 0;
DISPLAY LEFT (4950 6275);
DISPLAY 2.510638 (4950 6275);
PAINT WHITE (4950 6275);
QUIT
